FILE_TYPE = MACRO_DRAWING;
SET COLOR_WIRE YELLOW;
SET COLOR_PROP MONO;
SET COLOR_DOT WHITE;
SET COLOR_ARC YELLOW;
SET COLOR_BODY GREEN;
SET COLOR_NOTE MONO;
SET PROP_DISPLAY VALUE;
SET PAGE_NUMBER P26;
FORCEADD OFFPAGE..5
(-6350 525);
FORCEPROP 2 LAST $XR0 49 
J 0
(-6574 525);
DISPLAY 0.638298 (-6574 525);
PAINT MONO (-6574 525);
FORCEPROP 2 LAST $XR1 50 
J 0
(-6664 525);
DISPLAY 0.638298 (-6664 525);
PAINT MONO (-6664 525);
FORCEPROP 2 LAST CDS_LIB mstr_standard
J 0
(-6350 525);
PAINT MONO (-6350 525);
DISPLAY INVISIBLE (-6350 525);
FORCEPROP 1 LAST OFFPAGE TRUE
J 0
(-6025 400);
DISPLAY 1.170213 (-6025 400);
PAINT GREEN (-6025 400);
DISPLAY INVISIBLE (-6025 400);
FORCEPROP 1 LAST COMMENT_BODY TRUE
J 0
(-6250 450);
DISPLAY 1.170213 (-6250 450);
PAINT GREEN (-6250 450);
DISPLAY INVISIBLE (-6250 450);
FORCEPROP 2 LAST PATH I1
J 0
(-6300 600);
DISPLAY 1.021277 (-6300 600);
PAINT ORANGE (-6300 600);
DISPLAY INVISIBLE (-6300 600);
FORCEADD TAP..6
(-5500 875);
FORCEPROP 3 LASTPIN (-5450 875) SIG_NAME M_D_CLK_DP<1>
J 0
(-5440 885);
DISPLAY 0.659574 (-5440 885);
PAINT MONO (-5440 885);
DISPLAY INVISIBLE (-5440 885);
FORCEPROP 1 LASTPIN (-5450 875) BN 1
J 0
(-5502 883);
DISPLAY 0.617021 (-5502 883);
PAINT PINK (-5502 883);
FORCEPROP 2 LAST CDS_LIB mstr_standard
J 0
(-5500 875);
PAINT MONO (-5500 875);
DISPLAY INVISIBLE (-5500 875);
FORCEPROP 1 LAST BODY_TYPE PLUMBING
J 0
(-5500 825);
DISPLAY 1.595745 (-5500 825);
PAINT GREEN (-5500 825);
DISPLAY INVISIBLE (-5500 825);
FORCEPROP 1 LAST HDL_TAP TRUE
J 0
(-5175 750);
DISPLAY 1.595745 (-5175 750);
PAINT GREEN (-5175 750);
DISPLAY INVISIBLE (-5175 750);
FORCEPROP 1 LAST PATH I10
J 0
(-5502 875);
DISPLAY 0.872340 (-5502 875);
PAINT GREEN (-5502 875);
DISPLAY INVISIBLE (-5502 875);
FORCEADD TAP..6
R 2
(-2775 1525);
FORCEPROP 3 LASTPIN (-2825 1525) SIG_NAME M_D_ODT<2>
J 0
(-2815 1535);
DISPLAY 0.659574 (-2815 1535);
PAINT MONO (-2815 1535);
DISPLAY INVISIBLE (-2815 1535);
FORCEPROP 1 LASTPIN (-2825 1525) BN 2
J 2
(-2773 1533);
DISPLAY 0.617021 (-2773 1533);
PAINT PINK (-2773 1533);
FORCEPROP 2 LAST CDS_LIB mstr_standard
J 0
(-2775 1525);
PAINT MONO (-2775 1525);
DISPLAY INVISIBLE (-2775 1525);
FORCEPROP 1 LAST BODY_TYPE PLUMBING
J 2
(-2775 1475);
DISPLAY 1.595745 (-2775 1475);
PAINT GREEN (-2775 1475);
DISPLAY INVISIBLE (-2775 1475);
FORCEPROP 1 LAST HDL_TAP TRUE
J 2
(-3100 1400);
DISPLAY 1.595745 (-3100 1400);
PAINT GREEN (-3100 1400);
DISPLAY INVISIBLE (-3100 1400);
FORCEPROP 1 LAST PATH I100
J 2
(-2773 1525);
DISPLAY 0.872340 (-2773 1525);
PAINT GREEN (-2773 1525);
DISPLAY INVISIBLE (-2773 1525);
FORCEADD TAP..6
R 2
(-2775 1575);
FORCEPROP 3 LASTPIN (-2825 1575) SIG_NAME M_D_ODT<3>
J 0
(-2815 1585);
DISPLAY 0.659574 (-2815 1585);
PAINT MONO (-2815 1585);
DISPLAY INVISIBLE (-2815 1585);
FORCEPROP 1 LASTPIN (-2825 1575) BN 3
J 2
(-2773 1583);
DISPLAY 0.617021 (-2773 1583);
PAINT PINK (-2773 1583);
FORCEPROP 2 LAST CDS_LIB mstr_standard
J 0
(-2775 1575);
PAINT MONO (-2775 1575);
DISPLAY INVISIBLE (-2775 1575);
FORCEPROP 1 LAST BODY_TYPE PLUMBING
J 2
(-2775 1525);
DISPLAY 1.595745 (-2775 1525);
PAINT GREEN (-2775 1525);
DISPLAY INVISIBLE (-2775 1525);
FORCEPROP 1 LAST HDL_TAP TRUE
J 2
(-3100 1450);
DISPLAY 1.595745 (-3100 1450);
PAINT GREEN (-3100 1450);
DISPLAY INVISIBLE (-3100 1450);
FORCEPROP 1 LAST PATH I101
J 2
(-2773 1575);
DISPLAY 0.872340 (-2773 1575);
PAINT GREEN (-2773 1575);
DISPLAY INVISIBLE (-2773 1575);
FORCEADD TAP..6
R 2
(-2775 1475);
FORCEPROP 3 LASTPIN (-2825 1475) SIG_NAME M_D_ODT<1>
J 0
(-2815 1485);
DISPLAY 0.659574 (-2815 1485);
PAINT MONO (-2815 1485);
DISPLAY INVISIBLE (-2815 1485);
FORCEPROP 1 LASTPIN (-2825 1475) BN 1
J 2
(-2773 1483);
DISPLAY 0.617021 (-2773 1483);
PAINT PINK (-2773 1483);
FORCEPROP 2 LAST CDS_LIB mstr_standard
J 0
(-2775 1475);
PAINT MONO (-2775 1475);
DISPLAY INVISIBLE (-2775 1475);
FORCEPROP 1 LAST BODY_TYPE PLUMBING
J 2
(-2775 1425);
DISPLAY 1.595745 (-2775 1425);
PAINT GREEN (-2775 1425);
DISPLAY INVISIBLE (-2775 1425);
FORCEPROP 1 LAST HDL_TAP TRUE
J 2
(-3100 1350);
DISPLAY 1.595745 (-3100 1350);
PAINT GREEN (-3100 1350);
DISPLAY INVISIBLE (-3100 1350);
FORCEPROP 1 LAST PATH I102
J 2
(-2773 1475);
DISPLAY 0.872340 (-2773 1475);
PAINT GREEN (-2773 1475);
DISPLAY INVISIBLE (-2773 1475);
FORCEADD TAP..6
R 2
(-2775 1675);
FORCEPROP 3 LASTPIN (-2825 1675) SIG_NAME M_D_CKE<0>
J 0
(-2815 1685);
DISPLAY 0.659574 (-2815 1685);
PAINT MONO (-2815 1685);
DISPLAY INVISIBLE (-2815 1685);
FORCEPROP 1 LASTPIN (-2825 1675) BN 0
J 2
(-2773 1683);
DISPLAY 0.617021 (-2773 1683);
PAINT PINK (-2773 1683);
FORCEPROP 2 LAST CDS_LIB mstr_standard
J 0
(-2775 1675);
PAINT MONO (-2775 1675);
DISPLAY INVISIBLE (-2775 1675);
FORCEPROP 1 LAST BODY_TYPE PLUMBING
J 2
(-2775 1625);
DISPLAY 1.595745 (-2775 1625);
PAINT GREEN (-2775 1625);
DISPLAY INVISIBLE (-2775 1625);
FORCEPROP 1 LAST HDL_TAP TRUE
J 2
(-3100 1550);
DISPLAY 1.595745 (-3100 1550);
PAINT GREEN (-3100 1550);
DISPLAY INVISIBLE (-3100 1550);
FORCEPROP 1 LAST PATH I103
J 2
(-2773 1675);
DISPLAY 0.872340 (-2773 1675);
PAINT GREEN (-2773 1675);
DISPLAY INVISIBLE (-2773 1675);
FORCEADD TAP..6
R 2
(-2775 1725);
FORCEPROP 3 LASTPIN (-2825 1725) SIG_NAME M_D_CKE<1>
J 0
(-2815 1735);
DISPLAY 0.659574 (-2815 1735);
PAINT MONO (-2815 1735);
DISPLAY INVISIBLE (-2815 1735);
FORCEPROP 1 LASTPIN (-2825 1725) BN 1
J 2
(-2773 1733);
DISPLAY 0.617021 (-2773 1733);
PAINT PINK (-2773 1733);
FORCEPROP 2 LAST CDS_LIB mstr_standard
J 0
(-2775 1725);
PAINT MONO (-2775 1725);
DISPLAY INVISIBLE (-2775 1725);
FORCEPROP 1 LAST BODY_TYPE PLUMBING
J 2
(-2775 1675);
DISPLAY 1.595745 (-2775 1675);
PAINT GREEN (-2775 1675);
DISPLAY INVISIBLE (-2775 1675);
FORCEPROP 1 LAST HDL_TAP TRUE
J 2
(-3100 1600);
DISPLAY 1.595745 (-3100 1600);
PAINT GREEN (-3100 1600);
DISPLAY INVISIBLE (-3100 1600);
FORCEPROP 1 LAST PATH I104
J 2
(-2773 1725);
DISPLAY 0.872340 (-2773 1725);
PAINT GREEN (-2773 1725);
DISPLAY INVISIBLE (-2773 1725);
FORCEADD TAP..6
R 2
(-2775 1775);
FORCEPROP 3 LASTPIN (-2825 1775) SIG_NAME M_D_CKE<2>
J 0
(-2815 1785);
DISPLAY 0.659574 (-2815 1785);
PAINT MONO (-2815 1785);
DISPLAY INVISIBLE (-2815 1785);
FORCEPROP 1 LASTPIN (-2825 1775) BN 2
J 2
(-2773 1783);
DISPLAY 0.617021 (-2773 1783);
PAINT PINK (-2773 1783);
FORCEPROP 2 LAST CDS_LIB mstr_standard
J 0
(-2775 1775);
PAINT MONO (-2775 1775);
DISPLAY INVISIBLE (-2775 1775);
FORCEPROP 1 LAST BODY_TYPE PLUMBING
J 2
(-2775 1725);
DISPLAY 1.595745 (-2775 1725);
PAINT GREEN (-2775 1725);
DISPLAY INVISIBLE (-2775 1725);
FORCEPROP 1 LAST HDL_TAP TRUE
J 2
(-3100 1650);
DISPLAY 1.595745 (-3100 1650);
PAINT GREEN (-3100 1650);
DISPLAY INVISIBLE (-3100 1650);
FORCEPROP 1 LAST PATH I105
J 2
(-2773 1775);
DISPLAY 0.872340 (-2773 1775);
PAINT GREEN (-2773 1775);
DISPLAY INVISIBLE (-2773 1775);
FORCEADD TAP..6
R 2
(-2775 1825);
FORCEPROP 3 LASTPIN (-2825 1825) SIG_NAME M_D_CKE<3>
J 0
(-2815 1835);
DISPLAY 0.659574 (-2815 1835);
PAINT MONO (-2815 1835);
DISPLAY INVISIBLE (-2815 1835);
FORCEPROP 1 LASTPIN (-2825 1825) BN 3
J 2
(-2773 1833);
DISPLAY 0.617021 (-2773 1833);
PAINT PINK (-2773 1833);
FORCEPROP 2 LAST CDS_LIB mstr_standard
J 0
(-2775 1825);
PAINT MONO (-2775 1825);
DISPLAY INVISIBLE (-2775 1825);
FORCEPROP 1 LAST BODY_TYPE PLUMBING
J 2
(-2775 1775);
DISPLAY 1.595745 (-2775 1775);
PAINT GREEN (-2775 1775);
DISPLAY INVISIBLE (-2775 1775);
FORCEPROP 1 LAST HDL_TAP TRUE
J 2
(-3100 1700);
DISPLAY 1.595745 (-3100 1700);
PAINT GREEN (-3100 1700);
DISPLAY INVISIBLE (-3100 1700);
FORCEPROP 1 LAST PATH I106
J 2
(-2773 1825);
DISPLAY 0.872340 (-2773 1825);
PAINT GREEN (-2773 1825);
DISPLAY INVISIBLE (-2773 1825);
FORCEADD TAP..6
R 2
(-2775 1925);
FORCEPROP 3 LASTPIN (-2825 1925) SIG_NAME M_D_MA<0>
J 0
(-2815 1935);
DISPLAY 0.659574 (-2815 1935);
PAINT MONO (-2815 1935);
DISPLAY INVISIBLE (-2815 1935);
FORCEPROP 1 LASTPIN (-2825 1925) BN 0
J 2
(-2773 1933);
DISPLAY 0.617021 (-2773 1933);
PAINT PINK (-2773 1933);
FORCEPROP 2 LAST CDS_LIB mstr_standard
J 0
(-2775 1925);
PAINT MONO (-2775 1925);
DISPLAY INVISIBLE (-2775 1925);
FORCEPROP 1 LAST BODY_TYPE PLUMBING
J 2
(-2775 1875);
DISPLAY 1.595745 (-2775 1875);
PAINT GREEN (-2775 1875);
DISPLAY INVISIBLE (-2775 1875);
FORCEPROP 1 LAST HDL_TAP TRUE
J 2
(-3100 1800);
DISPLAY 1.595745 (-3100 1800);
PAINT GREEN (-3100 1800);
DISPLAY INVISIBLE (-3100 1800);
FORCEPROP 1 LAST PATH I107
J 2
(-2773 1925);
DISPLAY 0.872340 (-2773 1925);
PAINT GREEN (-2773 1925);
DISPLAY INVISIBLE (-2773 1925);
FORCEADD TAP..6
R 2
(-2775 1975);
FORCEPROP 3 LASTPIN (-2825 1975) SIG_NAME M_D_MA<1>
J 0
(-2815 1985);
DISPLAY 0.659574 (-2815 1985);
PAINT MONO (-2815 1985);
DISPLAY INVISIBLE (-2815 1985);
FORCEPROP 1 LASTPIN (-2825 1975) BN 1
J 2
(-2773 1983);
DISPLAY 0.617021 (-2773 1983);
PAINT PINK (-2773 1983);
FORCEPROP 2 LAST CDS_LIB mstr_standard
J 0
(-2775 1975);
PAINT MONO (-2775 1975);
DISPLAY INVISIBLE (-2775 1975);
FORCEPROP 1 LAST BODY_TYPE PLUMBING
J 2
(-2775 1925);
DISPLAY 1.595745 (-2775 1925);
PAINT GREEN (-2775 1925);
DISPLAY INVISIBLE (-2775 1925);
FORCEPROP 1 LAST HDL_TAP TRUE
J 2
(-3100 1850);
DISPLAY 1.595745 (-3100 1850);
PAINT GREEN (-3100 1850);
DISPLAY INVISIBLE (-3100 1850);
FORCEPROP 1 LAST PATH I108
J 2
(-2773 1975);
DISPLAY 0.872340 (-2773 1975);
PAINT GREEN (-2773 1975);
DISPLAY INVISIBLE (-2773 1975);
FORCEADD TAP..6
R 2
(-2775 2075);
FORCEPROP 3 LASTPIN (-2825 2075) SIG_NAME M_D_MA<3>
J 0
(-2815 2085);
DISPLAY 0.659574 (-2815 2085);
PAINT MONO (-2815 2085);
DISPLAY INVISIBLE (-2815 2085);
FORCEPROP 1 LASTPIN (-2825 2075) BN 3
J 2
(-2773 2083);
DISPLAY 0.617021 (-2773 2083);
PAINT PINK (-2773 2083);
FORCEPROP 2 LAST CDS_LIB mstr_standard
J 0
(-2775 2075);
PAINT MONO (-2775 2075);
DISPLAY INVISIBLE (-2775 2075);
FORCEPROP 1 LAST BODY_TYPE PLUMBING
J 2
(-2775 2025);
DISPLAY 1.595745 (-2775 2025);
PAINT GREEN (-2775 2025);
DISPLAY INVISIBLE (-2775 2025);
FORCEPROP 1 LAST HDL_TAP TRUE
J 2
(-3100 1950);
DISPLAY 1.595745 (-3100 1950);
PAINT GREEN (-3100 1950);
DISPLAY INVISIBLE (-3100 1950);
FORCEPROP 1 LAST PATH I109
J 2
(-2773 2075);
DISPLAY 0.872340 (-2773 2075);
PAINT GREEN (-2773 2075);
DISPLAY INVISIBLE (-2773 2075);
FORCEADD TAP..6
(-5500 925);
FORCEPROP 3 LASTPIN (-5450 925) SIG_NAME M_D_CLK_DP<2>
J 0
(-5440 935);
DISPLAY 0.659574 (-5440 935);
PAINT MONO (-5440 935);
DISPLAY INVISIBLE (-5440 935);
FORCEPROP 1 LASTPIN (-5450 925) BN 2
J 0
(-5502 933);
DISPLAY 0.617021 (-5502 933);
PAINT PINK (-5502 933);
FORCEPROP 2 LAST CDS_LIB mstr_standard
J 0
(-5500 925);
PAINT MONO (-5500 925);
DISPLAY INVISIBLE (-5500 925);
FORCEPROP 1 LAST BODY_TYPE PLUMBING
J 0
(-5500 875);
DISPLAY 1.595745 (-5500 875);
PAINT GREEN (-5500 875);
DISPLAY INVISIBLE (-5500 875);
FORCEPROP 1 LAST HDL_TAP TRUE
J 0
(-5175 800);
DISPLAY 1.595745 (-5175 800);
PAINT GREEN (-5175 800);
DISPLAY INVISIBLE (-5175 800);
FORCEPROP 1 LAST PATH I11
J 0
(-5502 925);
DISPLAY 0.872340 (-5502 925);
PAINT GREEN (-5502 925);
DISPLAY INVISIBLE (-5502 925);
FORCEADD TAP..6
R 2
(-2775 2025);
FORCEPROP 3 LASTPIN (-2825 2025) SIG_NAME M_D_MA<2>
J 0
(-2815 2035);
DISPLAY 0.659574 (-2815 2035);
PAINT MONO (-2815 2035);
DISPLAY INVISIBLE (-2815 2035);
FORCEPROP 1 LASTPIN (-2825 2025) BN 2
J 2
(-2773 2033);
DISPLAY 0.617021 (-2773 2033);
PAINT PINK (-2773 2033);
FORCEPROP 2 LAST CDS_LIB mstr_standard
J 0
(-2775 2025);
PAINT MONO (-2775 2025);
DISPLAY INVISIBLE (-2775 2025);
FORCEPROP 1 LAST BODY_TYPE PLUMBING
J 2
(-2775 1975);
DISPLAY 1.595745 (-2775 1975);
PAINT GREEN (-2775 1975);
DISPLAY INVISIBLE (-2775 1975);
FORCEPROP 1 LAST HDL_TAP TRUE
J 2
(-3100 1900);
DISPLAY 1.595745 (-3100 1900);
PAINT GREEN (-3100 1900);
DISPLAY INVISIBLE (-3100 1900);
FORCEPROP 1 LAST PATH I110
J 2
(-2773 2025);
DISPLAY 0.872340 (-2773 2025);
PAINT GREEN (-2773 2025);
DISPLAY INVISIBLE (-2773 2025);
FORCEADD TAP..6
R 2
(-2775 2125);
FORCEPROP 3 LASTPIN (-2825 2125) SIG_NAME M_D_MA<4>
J 0
(-2815 2135);
DISPLAY 0.659574 (-2815 2135);
PAINT MONO (-2815 2135);
DISPLAY INVISIBLE (-2815 2135);
FORCEPROP 1 LASTPIN (-2825 2125) BN 4
J 2
(-2773 2133);
DISPLAY 0.617021 (-2773 2133);
PAINT PINK (-2773 2133);
FORCEPROP 2 LAST CDS_LIB mstr_standard
J 0
(-2775 2125);
PAINT MONO (-2775 2125);
DISPLAY INVISIBLE (-2775 2125);
FORCEPROP 1 LAST BODY_TYPE PLUMBING
J 2
(-2775 2075);
DISPLAY 1.595745 (-2775 2075);
PAINT GREEN (-2775 2075);
DISPLAY INVISIBLE (-2775 2075);
FORCEPROP 1 LAST HDL_TAP TRUE
J 2
(-3100 2000);
DISPLAY 1.595745 (-3100 2000);
PAINT GREEN (-3100 2000);
DISPLAY INVISIBLE (-3100 2000);
FORCEPROP 1 LAST PATH I111
J 2
(-2773 2125);
DISPLAY 0.872340 (-2773 2125);
PAINT GREEN (-2773 2125);
DISPLAY INVISIBLE (-2773 2125);
FORCEADD TAP..6
R 2
(-2775 2225);
FORCEPROP 3 LASTPIN (-2825 2225) SIG_NAME M_D_MA<6>
J 0
(-2815 2235);
DISPLAY 0.659574 (-2815 2235);
PAINT MONO (-2815 2235);
DISPLAY INVISIBLE (-2815 2235);
FORCEPROP 1 LASTPIN (-2825 2225) BN 6
J 2
(-2773 2233);
DISPLAY 0.617021 (-2773 2233);
PAINT PINK (-2773 2233);
FORCEPROP 2 LAST CDS_LIB mstr_standard
J 0
(-2775 2225);
PAINT MONO (-2775 2225);
DISPLAY INVISIBLE (-2775 2225);
FORCEPROP 1 LAST BODY_TYPE PLUMBING
J 2
(-2775 2175);
DISPLAY 1.595745 (-2775 2175);
PAINT GREEN (-2775 2175);
DISPLAY INVISIBLE (-2775 2175);
FORCEPROP 1 LAST HDL_TAP TRUE
J 2
(-3100 2100);
DISPLAY 1.595745 (-3100 2100);
PAINT GREEN (-3100 2100);
DISPLAY INVISIBLE (-3100 2100);
FORCEPROP 1 LAST PATH I112
J 2
(-2773 2225);
DISPLAY 0.872340 (-2773 2225);
PAINT GREEN (-2773 2225);
DISPLAY INVISIBLE (-2773 2225);
FORCEADD TAP..6
R 2
(-2775 2175);
FORCEPROP 3 LASTPIN (-2825 2175) SIG_NAME M_D_MA<5>
J 0
(-2815 2185);
DISPLAY 0.659574 (-2815 2185);
PAINT MONO (-2815 2185);
DISPLAY INVISIBLE (-2815 2185);
FORCEPROP 1 LASTPIN (-2825 2175) BN 5
J 2
(-2773 2183);
DISPLAY 0.617021 (-2773 2183);
PAINT PINK (-2773 2183);
FORCEPROP 2 LAST CDS_LIB mstr_standard
J 0
(-2775 2175);
PAINT MONO (-2775 2175);
DISPLAY INVISIBLE (-2775 2175);
FORCEPROP 1 LAST BODY_TYPE PLUMBING
J 2
(-2775 2125);
DISPLAY 1.595745 (-2775 2125);
PAINT GREEN (-2775 2125);
DISPLAY INVISIBLE (-2775 2125);
FORCEPROP 1 LAST HDL_TAP TRUE
J 2
(-3100 2050);
DISPLAY 1.595745 (-3100 2050);
PAINT GREEN (-3100 2050);
DISPLAY INVISIBLE (-3100 2050);
FORCEPROP 1 LAST PATH I113
J 2
(-2773 2175);
DISPLAY 0.872340 (-2773 2175);
PAINT GREEN (-2773 2175);
DISPLAY INVISIBLE (-2773 2175);
FORCEADD TAP..6
R 2
(-2775 2275);
FORCEPROP 3 LASTPIN (-2825 2275) SIG_NAME M_D_MA<7>
J 0
(-2815 2285);
DISPLAY 0.659574 (-2815 2285);
PAINT MONO (-2815 2285);
DISPLAY INVISIBLE (-2815 2285);
FORCEPROP 1 LASTPIN (-2825 2275) BN 7
J 2
(-2773 2283);
DISPLAY 0.617021 (-2773 2283);
PAINT PINK (-2773 2283);
FORCEPROP 2 LAST CDS_LIB mstr_standard
J 0
(-2775 2275);
PAINT MONO (-2775 2275);
DISPLAY INVISIBLE (-2775 2275);
FORCEPROP 1 LAST BODY_TYPE PLUMBING
J 2
(-2775 2225);
DISPLAY 1.595745 (-2775 2225);
PAINT GREEN (-2775 2225);
DISPLAY INVISIBLE (-2775 2225);
FORCEPROP 1 LAST HDL_TAP TRUE
J 2
(-3100 2150);
DISPLAY 1.595745 (-3100 2150);
PAINT GREEN (-3100 2150);
DISPLAY INVISIBLE (-3100 2150);
FORCEPROP 1 LAST PATH I114
J 2
(-2773 2275);
DISPLAY 0.872340 (-2773 2275);
PAINT GREEN (-2773 2275);
DISPLAY INVISIBLE (-2773 2275);
FORCEADD TAP..6
R 2
(-2775 2325);
FORCEPROP 3 LASTPIN (-2825 2325) SIG_NAME M_D_MA<8>
J 0
(-2815 2335);
DISPLAY 0.659574 (-2815 2335);
PAINT MONO (-2815 2335);
DISPLAY INVISIBLE (-2815 2335);
FORCEPROP 1 LASTPIN (-2825 2325) BN 8
J 2
(-2773 2333);
DISPLAY 0.617021 (-2773 2333);
PAINT PINK (-2773 2333);
FORCEPROP 2 LAST CDS_LIB mstr_standard
J 0
(-2775 2325);
PAINT MONO (-2775 2325);
DISPLAY INVISIBLE (-2775 2325);
FORCEPROP 1 LAST BODY_TYPE PLUMBING
J 2
(-2775 2275);
DISPLAY 1.595745 (-2775 2275);
PAINT GREEN (-2775 2275);
DISPLAY INVISIBLE (-2775 2275);
FORCEPROP 1 LAST HDL_TAP TRUE
J 2
(-3100 2200);
DISPLAY 1.595745 (-3100 2200);
PAINT GREEN (-3100 2200);
DISPLAY INVISIBLE (-3100 2200);
FORCEPROP 1 LAST PATH I115
J 2
(-2773 2325);
DISPLAY 0.872340 (-2773 2325);
PAINT GREEN (-2773 2325);
DISPLAY INVISIBLE (-2773 2325);
FORCEADD TAP..6
R 2
(-2775 2375);
FORCEPROP 3 LASTPIN (-2825 2375) SIG_NAME M_D_MA<9>
J 0
(-2815 2385);
DISPLAY 0.659574 (-2815 2385);
PAINT MONO (-2815 2385);
DISPLAY INVISIBLE (-2815 2385);
FORCEPROP 1 LASTPIN (-2825 2375) BN 9
J 2
(-2773 2383);
DISPLAY 0.617021 (-2773 2383);
PAINT PINK (-2773 2383);
FORCEPROP 2 LAST CDS_LIB mstr_standard
J 0
(-2775 2375);
PAINT MONO (-2775 2375);
DISPLAY INVISIBLE (-2775 2375);
FORCEPROP 1 LAST BODY_TYPE PLUMBING
J 2
(-2775 2325);
DISPLAY 1.595745 (-2775 2325);
PAINT GREEN (-2775 2325);
DISPLAY INVISIBLE (-2775 2325);
FORCEPROP 1 LAST HDL_TAP TRUE
J 2
(-3100 2250);
DISPLAY 1.595745 (-3100 2250);
PAINT GREEN (-3100 2250);
DISPLAY INVISIBLE (-3100 2250);
FORCEPROP 1 LAST PATH I116
J 2
(-2773 2375);
DISPLAY 0.872340 (-2773 2375);
PAINT GREEN (-2773 2375);
DISPLAY INVISIBLE (-2773 2375);
FORCEADD TAP..6
R 2
(-2775 2425);
FORCEPROP 3 LASTPIN (-2825 2425) SIG_NAME M_D_MA<10>
J 0
(-2815 2435);
DISPLAY 0.659574 (-2815 2435);
PAINT MONO (-2815 2435);
DISPLAY INVISIBLE (-2815 2435);
FORCEPROP 1 LASTPIN (-2825 2425) BN 10
J 2
(-2773 2433);
DISPLAY 0.617021 (-2773 2433);
PAINT PINK (-2773 2433);
FORCEPROP 2 LAST CDS_LIB mstr_standard
J 0
(-2775 2425);
PAINT MONO (-2775 2425);
DISPLAY INVISIBLE (-2775 2425);
FORCEPROP 1 LAST BODY_TYPE PLUMBING
J 2
(-2775 2375);
DISPLAY 1.595745 (-2775 2375);
PAINT GREEN (-2775 2375);
DISPLAY INVISIBLE (-2775 2375);
FORCEPROP 1 LAST HDL_TAP TRUE
J 2
(-3100 2300);
DISPLAY 1.595745 (-3100 2300);
PAINT GREEN (-3100 2300);
DISPLAY INVISIBLE (-3100 2300);
FORCEPROP 1 LAST PATH I117
J 2
(-2773 2425);
DISPLAY 0.872340 (-2773 2425);
PAINT GREEN (-2773 2425);
DISPLAY INVISIBLE (-2773 2425);
FORCEADD TAP..6
R 2
(-2775 2475);
FORCEPROP 3 LASTPIN (-2825 2475) SIG_NAME M_D_MA<11>
J 0
(-2815 2485);
DISPLAY 0.659574 (-2815 2485);
PAINT MONO (-2815 2485);
DISPLAY INVISIBLE (-2815 2485);
FORCEPROP 1 LASTPIN (-2825 2475) BN 11
J 2
(-2773 2483);
DISPLAY 0.617021 (-2773 2483);
PAINT PINK (-2773 2483);
FORCEPROP 2 LAST CDS_LIB mstr_standard
J 0
(-2775 2475);
PAINT MONO (-2775 2475);
DISPLAY INVISIBLE (-2775 2475);
FORCEPROP 1 LAST BODY_TYPE PLUMBING
J 2
(-2775 2425);
DISPLAY 1.595745 (-2775 2425);
PAINT GREEN (-2775 2425);
DISPLAY INVISIBLE (-2775 2425);
FORCEPROP 1 LAST HDL_TAP TRUE
J 2
(-3100 2350);
DISPLAY 1.595745 (-3100 2350);
PAINT GREEN (-3100 2350);
DISPLAY INVISIBLE (-3100 2350);
FORCEPROP 1 LAST PATH I118
J 2
(-2773 2475);
DISPLAY 0.872340 (-2773 2475);
PAINT GREEN (-2773 2475);
DISPLAY INVISIBLE (-2773 2475);
FORCEADD TAP..6
R 2
(-2775 2575);
FORCEPROP 3 LASTPIN (-2825 2575) SIG_NAME M_D_MA<13>
J 0
(-2815 2585);
DISPLAY 0.659574 (-2815 2585);
PAINT MONO (-2815 2585);
DISPLAY INVISIBLE (-2815 2585);
FORCEPROP 1 LASTPIN (-2825 2575) BN 13
J 2
(-2773 2583);
DISPLAY 0.617021 (-2773 2583);
PAINT PINK (-2773 2583);
FORCEPROP 2 LAST CDS_LIB mstr_standard
J 0
(-2775 2575);
PAINT MONO (-2775 2575);
DISPLAY INVISIBLE (-2775 2575);
FORCEPROP 1 LAST BODY_TYPE PLUMBING
J 2
(-2775 2525);
DISPLAY 1.595745 (-2775 2525);
PAINT GREEN (-2775 2525);
DISPLAY INVISIBLE (-2775 2525);
FORCEPROP 1 LAST HDL_TAP TRUE
J 2
(-3100 2450);
DISPLAY 1.595745 (-3100 2450);
PAINT GREEN (-3100 2450);
DISPLAY INVISIBLE (-3100 2450);
FORCEPROP 1 LAST PATH I119
J 2
(-2773 2575);
DISPLAY 0.872340 (-2773 2575);
PAINT GREEN (-2773 2575);
DISPLAY INVISIBLE (-2773 2575);
FORCEADD TAP..6
(-5500 975);
FORCEPROP 3 LASTPIN (-5450 975) SIG_NAME M_D_CLK_DP<3>
J 0
(-5440 985);
DISPLAY 0.659574 (-5440 985);
PAINT MONO (-5440 985);
DISPLAY INVISIBLE (-5440 985);
FORCEPROP 1 LASTPIN (-5450 975) BN 3
J 0
(-5502 983);
DISPLAY 0.617021 (-5502 983);
PAINT PINK (-5502 983);
FORCEPROP 2 LAST CDS_LIB mstr_standard
J 0
(-5500 975);
PAINT MONO (-5500 975);
DISPLAY INVISIBLE (-5500 975);
FORCEPROP 1 LAST BODY_TYPE PLUMBING
J 0
(-5500 925);
DISPLAY 1.595745 (-5500 925);
PAINT GREEN (-5500 925);
DISPLAY INVISIBLE (-5500 925);
FORCEPROP 1 LAST HDL_TAP TRUE
J 0
(-5175 850);
DISPLAY 1.595745 (-5175 850);
PAINT GREEN (-5175 850);
DISPLAY INVISIBLE (-5175 850);
FORCEPROP 1 LAST PATH I12
J 0
(-5502 975);
DISPLAY 0.872340 (-5502 975);
PAINT GREEN (-5502 975);
DISPLAY INVISIBLE (-5502 975);
FORCEADD TAP..6
R 2
(-2775 2525);
FORCEPROP 3 LASTPIN (-2825 2525) SIG_NAME M_D_MA<12>
J 0
(-2815 2535);
DISPLAY 0.659574 (-2815 2535);
PAINT MONO (-2815 2535);
DISPLAY INVISIBLE (-2815 2535);
FORCEPROP 1 LASTPIN (-2825 2525) BN 12
J 2
(-2773 2533);
DISPLAY 0.617021 (-2773 2533);
PAINT PINK (-2773 2533);
FORCEPROP 2 LAST CDS_LIB mstr_standard
J 0
(-2775 2525);
PAINT MONO (-2775 2525);
DISPLAY INVISIBLE (-2775 2525);
FORCEPROP 1 LAST BODY_TYPE PLUMBING
J 2
(-2775 2475);
DISPLAY 1.595745 (-2775 2475);
PAINT GREEN (-2775 2475);
DISPLAY INVISIBLE (-2775 2475);
FORCEPROP 1 LAST HDL_TAP TRUE
J 2
(-3100 2400);
DISPLAY 1.595745 (-3100 2400);
PAINT GREEN (-3100 2400);
DISPLAY INVISIBLE (-3100 2400);
FORCEPROP 1 LAST PATH I120
J 2
(-2773 2525);
DISPLAY 0.872340 (-2773 2525);
PAINT GREEN (-2773 2525);
DISPLAY INVISIBLE (-2773 2525);
FORCEADD TAP..6
R 2
(-2775 2675);
FORCEPROP 3 LASTPIN (-2825 2675) SIG_NAME M_D_MA<15>
J 0
(-2815 2685);
DISPLAY 0.659574 (-2815 2685);
PAINT MONO (-2815 2685);
DISPLAY INVISIBLE (-2815 2685);
FORCEPROP 1 LASTPIN (-2825 2675) BN 15
J 2
(-2773 2683);
DISPLAY 0.617021 (-2773 2683);
PAINT PINK (-2773 2683);
FORCEPROP 2 LAST CDS_LIB mstr_standard
J 0
(-2775 2675);
PAINT MONO (-2775 2675);
DISPLAY INVISIBLE (-2775 2675);
FORCEPROP 1 LAST BODY_TYPE PLUMBING
J 2
(-2775 2625);
DISPLAY 1.595745 (-2775 2625);
PAINT GREEN (-2775 2625);
DISPLAY INVISIBLE (-2775 2625);
FORCEPROP 1 LAST HDL_TAP TRUE
J 2
(-3100 2550);
DISPLAY 1.595745 (-3100 2550);
PAINT GREEN (-3100 2550);
DISPLAY INVISIBLE (-3100 2550);
FORCEPROP 1 LAST PATH I121
J 2
(-2773 2675);
DISPLAY 0.872340 (-2773 2675);
PAINT GREEN (-2773 2675);
DISPLAY INVISIBLE (-2773 2675);
FORCEADD TAP..6
R 2
(-2775 2725);
FORCEPROP 3 LASTPIN (-2825 2725) SIG_NAME M_D_MA<16>
J 0
(-2815 2735);
DISPLAY 0.659574 (-2815 2735);
PAINT MONO (-2815 2735);
DISPLAY INVISIBLE (-2815 2735);
FORCEPROP 1 LASTPIN (-2825 2725) BN 16
J 2
(-2773 2733);
DISPLAY 0.617021 (-2773 2733);
PAINT PINK (-2773 2733);
FORCEPROP 2 LAST CDS_LIB mstr_standard
J 0
(-2775 2725);
PAINT MONO (-2775 2725);
DISPLAY INVISIBLE (-2775 2725);
FORCEPROP 1 LAST BODY_TYPE PLUMBING
J 2
(-2775 2675);
DISPLAY 1.595745 (-2775 2675);
PAINT GREEN (-2775 2675);
DISPLAY INVISIBLE (-2775 2675);
FORCEPROP 1 LAST HDL_TAP TRUE
J 2
(-3100 2600);
DISPLAY 1.595745 (-3100 2600);
PAINT GREEN (-3100 2600);
DISPLAY INVISIBLE (-3100 2600);
FORCEPROP 1 LAST PATH I122
J 2
(-2773 2725);
DISPLAY 0.872340 (-2773 2725);
PAINT GREEN (-2773 2725);
DISPLAY INVISIBLE (-2773 2725);
FORCEADD TAP..6
R 2
(-2775 2625);
FORCEPROP 3 LASTPIN (-2825 2625) SIG_NAME M_D_MA<14>
J 0
(-2815 2635);
DISPLAY 0.659574 (-2815 2635);
PAINT MONO (-2815 2635);
DISPLAY INVISIBLE (-2815 2635);
FORCEPROP 1 LASTPIN (-2825 2625) BN 14
J 2
(-2773 2633);
DISPLAY 0.617021 (-2773 2633);
PAINT PINK (-2773 2633);
FORCEPROP 2 LAST CDS_LIB mstr_standard
J 0
(-2775 2625);
PAINT MONO (-2775 2625);
DISPLAY INVISIBLE (-2775 2625);
FORCEPROP 1 LAST BODY_TYPE PLUMBING
J 2
(-2775 2575);
DISPLAY 1.595745 (-2775 2575);
PAINT GREEN (-2775 2575);
DISPLAY INVISIBLE (-2775 2575);
FORCEPROP 1 LAST HDL_TAP TRUE
J 2
(-3100 2500);
DISPLAY 1.595745 (-3100 2500);
PAINT GREEN (-3100 2500);
DISPLAY INVISIBLE (-3100 2500);
FORCEPROP 1 LAST PATH I123
J 2
(-2773 2625);
DISPLAY 0.872340 (-2773 2625);
PAINT GREEN (-2773 2625);
DISPLAY INVISIBLE (-2773 2625);
FORCEADD TAP..6
R 2
(-2775 2775);
FORCEPROP 3 LASTPIN (-2825 2775) SIG_NAME M_D_MA<17>
J 0
(-2815 2785);
DISPLAY 0.659574 (-2815 2785);
PAINT MONO (-2815 2785);
DISPLAY INVISIBLE (-2815 2785);
FORCEPROP 1 LASTPIN (-2825 2775) BN 17
J 2
(-2773 2783);
DISPLAY 0.617021 (-2773 2783);
PAINT PINK (-2773 2783);
FORCEPROP 2 LAST CDS_LIB mstr_standard
J 0
(-2775 2775);
PAINT MONO (-2775 2775);
DISPLAY INVISIBLE (-2775 2775);
FORCEPROP 1 LAST BODY_TYPE PLUMBING
J 2
(-2775 2725);
DISPLAY 1.595745 (-2775 2725);
PAINT GREEN (-2775 2725);
DISPLAY INVISIBLE (-2775 2725);
FORCEPROP 1 LAST HDL_TAP TRUE
J 2
(-3100 2650);
DISPLAY 1.595745 (-3100 2650);
PAINT GREEN (-3100 2650);
DISPLAY INVISIBLE (-3100 2650);
FORCEPROP 1 LAST PATH I124
J 2
(-2773 2775);
DISPLAY 0.872340 (-2773 2775);
PAINT GREEN (-2773 2775);
DISPLAY INVISIBLE (-2773 2775);
FORCEADD TAP..6
R 2
(-2775 2925);
FORCEPROP 3 LASTPIN (-2825 2925) SIG_NAME M_D_DQS_DN<1>
J 0
(-2815 2935);
DISPLAY 0.659574 (-2815 2935);
PAINT MONO (-2815 2935);
DISPLAY INVISIBLE (-2815 2935);
FORCEPROP 1 LASTPIN (-2825 2925) BN 1
J 2
(-2773 2933);
DISPLAY 0.617021 (-2773 2933);
PAINT PINK (-2773 2933);
FORCEPROP 2 LAST CDS_LIB mstr_standard
J 0
(-2775 2925);
PAINT MONO (-2775 2925);
DISPLAY INVISIBLE (-2775 2925);
FORCEPROP 1 LAST BODY_TYPE PLUMBING
J 2
(-2775 2875);
DISPLAY 1.595745 (-2775 2875);
PAINT GREEN (-2775 2875);
DISPLAY INVISIBLE (-2775 2875);
FORCEPROP 1 LAST HDL_TAP TRUE
J 2
(-3100 2800);
DISPLAY 1.595745 (-3100 2800);
PAINT GREEN (-3100 2800);
DISPLAY INVISIBLE (-3100 2800);
FORCEPROP 1 LAST PATH I125
J 2
(-2773 2925);
DISPLAY 0.872340 (-2773 2925);
PAINT GREEN (-2773 2925);
DISPLAY INVISIBLE (-2773 2925);
FORCEADD TAP..6
R 2
(-2775 2975);
FORCEPROP 3 LASTPIN (-2825 2975) SIG_NAME M_D_DQS_DN<2>
J 0
(-2815 2985);
DISPLAY 0.659574 (-2815 2985);
PAINT MONO (-2815 2985);
DISPLAY INVISIBLE (-2815 2985);
FORCEPROP 1 LASTPIN (-2825 2975) BN 2
J 2
(-2773 2983);
DISPLAY 0.617021 (-2773 2983);
PAINT PINK (-2773 2983);
FORCEPROP 2 LAST CDS_LIB mstr_standard
J 0
(-2775 2975);
PAINT MONO (-2775 2975);
DISPLAY INVISIBLE (-2775 2975);
FORCEPROP 1 LAST BODY_TYPE PLUMBING
J 2
(-2775 2925);
DISPLAY 1.595745 (-2775 2925);
PAINT GREEN (-2775 2925);
DISPLAY INVISIBLE (-2775 2925);
FORCEPROP 1 LAST HDL_TAP TRUE
J 2
(-3100 2850);
DISPLAY 1.595745 (-3100 2850);
PAINT GREEN (-3100 2850);
DISPLAY INVISIBLE (-3100 2850);
FORCEPROP 1 LAST PATH I126
J 2
(-2773 2975);
DISPLAY 0.872340 (-2773 2975);
PAINT GREEN (-2773 2975);
DISPLAY INVISIBLE (-2773 2975);
FORCEADD TAP..6
R 2
(-2775 2875);
FORCEPROP 3 LASTPIN (-2825 2875) SIG_NAME M_D_DQS_DN<0>
J 0
(-2815 2885);
DISPLAY 0.659574 (-2815 2885);
PAINT MONO (-2815 2885);
DISPLAY INVISIBLE (-2815 2885);
FORCEPROP 1 LASTPIN (-2825 2875) BN 0
J 2
(-2773 2883);
DISPLAY 0.617021 (-2773 2883);
PAINT PINK (-2773 2883);
FORCEPROP 2 LAST CDS_LIB mstr_standard
J 0
(-2775 2875);
PAINT MONO (-2775 2875);
DISPLAY INVISIBLE (-2775 2875);
FORCEPROP 1 LAST BODY_TYPE PLUMBING
J 2
(-2775 2825);
DISPLAY 1.595745 (-2775 2825);
PAINT GREEN (-2775 2825);
DISPLAY INVISIBLE (-2775 2825);
FORCEPROP 1 LAST HDL_TAP TRUE
J 2
(-3100 2750);
DISPLAY 1.595745 (-3100 2750);
PAINT GREEN (-3100 2750);
DISPLAY INVISIBLE (-3100 2750);
FORCEPROP 1 LAST PATH I127
J 2
(-2773 2875);
DISPLAY 0.872340 (-2773 2875);
PAINT GREEN (-2773 2875);
DISPLAY INVISIBLE (-2773 2875);
FORCEADD TAP..6
R 2
(-2775 3025);
FORCEPROP 3 LASTPIN (-2825 3025) SIG_NAME M_D_DQS_DN<3>
J 0
(-2815 3035);
DISPLAY 0.659574 (-2815 3035);
PAINT MONO (-2815 3035);
DISPLAY INVISIBLE (-2815 3035);
FORCEPROP 1 LASTPIN (-2825 3025) BN 3
J 2
(-2773 3033);
DISPLAY 0.617021 (-2773 3033);
PAINT PINK (-2773 3033);
FORCEPROP 2 LAST CDS_LIB mstr_standard
J 0
(-2775 3025);
PAINT MONO (-2775 3025);
DISPLAY INVISIBLE (-2775 3025);
FORCEPROP 1 LAST BODY_TYPE PLUMBING
J 2
(-2775 2975);
DISPLAY 1.595745 (-2775 2975);
PAINT GREEN (-2775 2975);
DISPLAY INVISIBLE (-2775 2975);
FORCEPROP 1 LAST HDL_TAP TRUE
J 2
(-3100 2900);
DISPLAY 1.595745 (-3100 2900);
PAINT GREEN (-3100 2900);
DISPLAY INVISIBLE (-3100 2900);
FORCEPROP 1 LAST PATH I128
J 2
(-2773 3025);
DISPLAY 0.872340 (-2773 3025);
PAINT GREEN (-2773 3025);
DISPLAY INVISIBLE (-2773 3025);
FORCEADD TAP..6
R 2
(-2775 3075);
FORCEPROP 3 LASTPIN (-2825 3075) SIG_NAME M_D_DQS_DN<4>
J 0
(-2815 3085);
DISPLAY 0.659574 (-2815 3085);
PAINT MONO (-2815 3085);
DISPLAY INVISIBLE (-2815 3085);
FORCEPROP 1 LASTPIN (-2825 3075) BN 4
J 2
(-2773 3083);
DISPLAY 0.617021 (-2773 3083);
PAINT PINK (-2773 3083);
FORCEPROP 2 LAST CDS_LIB mstr_standard
J 0
(-2775 3075);
PAINT MONO (-2775 3075);
DISPLAY INVISIBLE (-2775 3075);
FORCEPROP 1 LAST BODY_TYPE PLUMBING
J 2
(-2775 3025);
DISPLAY 1.595745 (-2775 3025);
PAINT GREEN (-2775 3025);
DISPLAY INVISIBLE (-2775 3025);
FORCEPROP 1 LAST HDL_TAP TRUE
J 2
(-3100 2950);
DISPLAY 1.595745 (-3100 2950);
PAINT GREEN (-3100 2950);
DISPLAY INVISIBLE (-3100 2950);
FORCEPROP 1 LAST PATH I129
J 2
(-2773 3075);
DISPLAY 0.872340 (-2773 3075);
PAINT GREEN (-2773 3075);
DISPLAY INVISIBLE (-2773 3075);
FORCEADD TAP..6
(-5500 1075);
FORCEPROP 3 LASTPIN (-5450 1075) SIG_NAME M_D_ECC<0>
J 0
(-5440 1085);
DISPLAY 0.659574 (-5440 1085);
PAINT MONO (-5440 1085);
DISPLAY INVISIBLE (-5440 1085);
FORCEPROP 1 LASTPIN (-5450 1075) BN 0
J 0
(-5502 1083);
DISPLAY 0.617021 (-5502 1083);
PAINT PINK (-5502 1083);
FORCEPROP 2 LAST CDS_LIB mstr_standard
J 0
(-5500 1075);
PAINT MONO (-5500 1075);
DISPLAY INVISIBLE (-5500 1075);
FORCEPROP 1 LAST BODY_TYPE PLUMBING
J 0
(-5500 1025);
DISPLAY 1.595745 (-5500 1025);
PAINT GREEN (-5500 1025);
DISPLAY INVISIBLE (-5500 1025);
FORCEPROP 1 LAST HDL_TAP TRUE
J 0
(-5175 950);
DISPLAY 1.595745 (-5175 950);
PAINT GREEN (-5175 950);
DISPLAY INVISIBLE (-5175 950);
FORCEPROP 1 LAST PATH I13
J 0
(-5502 1075);
DISPLAY 0.872340 (-5502 1075);
PAINT GREEN (-5502 1075);
DISPLAY INVISIBLE (-5502 1075);
FORCEADD TAP..6
R 2
(-2775 3125);
FORCEPROP 3 LASTPIN (-2825 3125) SIG_NAME M_D_DQS_DN<5>
J 0
(-2815 3135);
DISPLAY 0.659574 (-2815 3135);
PAINT MONO (-2815 3135);
DISPLAY INVISIBLE (-2815 3135);
FORCEPROP 1 LASTPIN (-2825 3125) BN 5
J 2
(-2773 3133);
DISPLAY 0.617021 (-2773 3133);
PAINT PINK (-2773 3133);
FORCEPROP 2 LAST CDS_LIB mstr_standard
J 0
(-2775 3125);
PAINT MONO (-2775 3125);
DISPLAY INVISIBLE (-2775 3125);
FORCEPROP 1 LAST BODY_TYPE PLUMBING
J 2
(-2775 3075);
DISPLAY 1.595745 (-2775 3075);
PAINT GREEN (-2775 3075);
DISPLAY INVISIBLE (-2775 3075);
FORCEPROP 1 LAST HDL_TAP TRUE
J 2
(-3100 3000);
DISPLAY 1.595745 (-3100 3000);
PAINT GREEN (-3100 3000);
DISPLAY INVISIBLE (-3100 3000);
FORCEPROP 1 LAST PATH I130
J 2
(-2773 3125);
DISPLAY 0.872340 (-2773 3125);
PAINT GREEN (-2773 3125);
DISPLAY INVISIBLE (-2773 3125);
FORCEADD TAP..6
R 2
(-2775 3175);
FORCEPROP 3 LASTPIN (-2825 3175) SIG_NAME M_D_DQS_DN<6>
J 0
(-2815 3185);
DISPLAY 0.659574 (-2815 3185);
PAINT MONO (-2815 3185);
DISPLAY INVISIBLE (-2815 3185);
FORCEPROP 1 LASTPIN (-2825 3175) BN 6
J 2
(-2773 3183);
DISPLAY 0.617021 (-2773 3183);
PAINT PINK (-2773 3183);
FORCEPROP 2 LAST CDS_LIB mstr_standard
J 0
(-2775 3175);
PAINT MONO (-2775 3175);
DISPLAY INVISIBLE (-2775 3175);
FORCEPROP 1 LAST BODY_TYPE PLUMBING
J 2
(-2775 3125);
DISPLAY 1.595745 (-2775 3125);
PAINT GREEN (-2775 3125);
DISPLAY INVISIBLE (-2775 3125);
FORCEPROP 1 LAST HDL_TAP TRUE
J 2
(-3100 3050);
DISPLAY 1.595745 (-3100 3050);
PAINT GREEN (-3100 3050);
DISPLAY INVISIBLE (-3100 3050);
FORCEPROP 1 LAST PATH I131
J 2
(-2773 3175);
DISPLAY 0.872340 (-2773 3175);
PAINT GREEN (-2773 3175);
DISPLAY INVISIBLE (-2773 3175);
FORCEADD TAP..6
R 2
(-2775 3225);
FORCEPROP 3 LASTPIN (-2825 3225) SIG_NAME M_D_DQS_DN<7>
J 0
(-2815 3235);
DISPLAY 0.659574 (-2815 3235);
PAINT MONO (-2815 3235);
DISPLAY INVISIBLE (-2815 3235);
FORCEPROP 1 LASTPIN (-2825 3225) BN 7
J 2
(-2773 3233);
DISPLAY 0.617021 (-2773 3233);
PAINT PINK (-2773 3233);
FORCEPROP 2 LAST CDS_LIB mstr_standard
J 0
(-2775 3225);
PAINT MONO (-2775 3225);
DISPLAY INVISIBLE (-2775 3225);
FORCEPROP 1 LAST BODY_TYPE PLUMBING
J 2
(-2775 3175);
DISPLAY 1.595745 (-2775 3175);
PAINT GREEN (-2775 3175);
DISPLAY INVISIBLE (-2775 3175);
FORCEPROP 1 LAST HDL_TAP TRUE
J 2
(-3100 3100);
DISPLAY 1.595745 (-3100 3100);
PAINT GREEN (-3100 3100);
DISPLAY INVISIBLE (-3100 3100);
FORCEPROP 1 LAST PATH I132
J 2
(-2773 3225);
DISPLAY 0.872340 (-2773 3225);
PAINT GREEN (-2773 3225);
DISPLAY INVISIBLE (-2773 3225);
FORCEADD TAP..6
R 2
(-2775 3275);
FORCEPROP 3 LASTPIN (-2825 3275) SIG_NAME M_D_DQS_DN<8>
J 0
(-2815 3285);
DISPLAY 0.659574 (-2815 3285);
PAINT MONO (-2815 3285);
DISPLAY INVISIBLE (-2815 3285);
FORCEPROP 1 LASTPIN (-2825 3275) BN 8
J 2
(-2773 3283);
DISPLAY 0.617021 (-2773 3283);
PAINT PINK (-2773 3283);
FORCEPROP 2 LAST CDS_LIB mstr_standard
J 0
(-2775 3275);
PAINT MONO (-2775 3275);
DISPLAY INVISIBLE (-2775 3275);
FORCEPROP 1 LAST BODY_TYPE PLUMBING
J 2
(-2775 3225);
DISPLAY 1.595745 (-2775 3225);
PAINT GREEN (-2775 3225);
DISPLAY INVISIBLE (-2775 3225);
FORCEPROP 1 LAST HDL_TAP TRUE
J 2
(-3100 3150);
DISPLAY 1.595745 (-3100 3150);
PAINT GREEN (-3100 3150);
DISPLAY INVISIBLE (-3100 3150);
FORCEPROP 1 LAST PATH I133
J 2
(-2773 3275);
DISPLAY 0.872340 (-2773 3275);
PAINT GREEN (-2773 3275);
DISPLAY INVISIBLE (-2773 3275);
FORCEADD TAP..6
R 2
(-2775 3325);
FORCEPROP 3 LASTPIN (-2825 3325) SIG_NAME M_D_DQS_DN<9>
J 0
(-2815 3335);
DISPLAY 0.659574 (-2815 3335);
PAINT MONO (-2815 3335);
DISPLAY INVISIBLE (-2815 3335);
FORCEPROP 1 LASTPIN (-2825 3325) BN 9
J 2
(-2773 3333);
DISPLAY 0.617021 (-2773 3333);
PAINT PINK (-2773 3333);
FORCEPROP 2 LAST CDS_LIB mstr_standard
J 0
(-2775 3325);
PAINT MONO (-2775 3325);
DISPLAY INVISIBLE (-2775 3325);
FORCEPROP 1 LAST BODY_TYPE PLUMBING
J 2
(-2775 3275);
DISPLAY 1.595745 (-2775 3275);
PAINT GREEN (-2775 3275);
DISPLAY INVISIBLE (-2775 3275);
FORCEPROP 1 LAST HDL_TAP TRUE
J 2
(-3100 3200);
DISPLAY 1.595745 (-3100 3200);
PAINT GREEN (-3100 3200);
DISPLAY INVISIBLE (-3100 3200);
FORCEPROP 1 LAST PATH I134
J 2
(-2773 3325);
DISPLAY 0.872340 (-2773 3325);
PAINT GREEN (-2773 3325);
DISPLAY INVISIBLE (-2773 3325);
FORCEADD TAP..6
R 2
(-2775 3375);
FORCEPROP 3 LASTPIN (-2825 3375) SIG_NAME M_D_DQS_DN<10>
J 0
(-2815 3385);
DISPLAY 0.659574 (-2815 3385);
PAINT MONO (-2815 3385);
DISPLAY INVISIBLE (-2815 3385);
FORCEPROP 1 LASTPIN (-2825 3375) BN 10
J 2
(-2773 3383);
DISPLAY 0.617021 (-2773 3383);
PAINT PINK (-2773 3383);
FORCEPROP 2 LAST CDS_LIB mstr_standard
J 0
(-2775 3375);
PAINT MONO (-2775 3375);
DISPLAY INVISIBLE (-2775 3375);
FORCEPROP 1 LAST BODY_TYPE PLUMBING
J 2
(-2775 3325);
DISPLAY 1.595745 (-2775 3325);
PAINT GREEN (-2775 3325);
DISPLAY INVISIBLE (-2775 3325);
FORCEPROP 1 LAST HDL_TAP TRUE
J 2
(-3100 3250);
DISPLAY 1.595745 (-3100 3250);
PAINT GREEN (-3100 3250);
DISPLAY INVISIBLE (-3100 3250);
FORCEPROP 1 LAST PATH I135
J 2
(-2773 3375);
DISPLAY 0.872340 (-2773 3375);
PAINT GREEN (-2773 3375);
DISPLAY INVISIBLE (-2773 3375);
FORCEADD TAP..6
R 2
(-2775 3475);
FORCEPROP 3 LASTPIN (-2825 3475) SIG_NAME M_D_DQS_DN<12>
J 0
(-2815 3485);
DISPLAY 0.659574 (-2815 3485);
PAINT MONO (-2815 3485);
DISPLAY INVISIBLE (-2815 3485);
FORCEPROP 1 LASTPIN (-2825 3475) BN 12
J 2
(-2773 3483);
DISPLAY 0.617021 (-2773 3483);
PAINT PINK (-2773 3483);
FORCEPROP 2 LAST CDS_LIB mstr_standard
J 0
(-2775 3475);
PAINT MONO (-2775 3475);
DISPLAY INVISIBLE (-2775 3475);
FORCEPROP 1 LAST BODY_TYPE PLUMBING
J 2
(-2775 3425);
DISPLAY 1.595745 (-2775 3425);
PAINT GREEN (-2775 3425);
DISPLAY INVISIBLE (-2775 3425);
FORCEPROP 1 LAST HDL_TAP TRUE
J 2
(-3100 3350);
DISPLAY 1.595745 (-3100 3350);
PAINT GREEN (-3100 3350);
DISPLAY INVISIBLE (-3100 3350);
FORCEPROP 1 LAST PATH I136
J 2
(-2773 3475);
DISPLAY 0.872340 (-2773 3475);
PAINT GREEN (-2773 3475);
DISPLAY INVISIBLE (-2773 3475);
FORCEADD TAP..6
R 2
(-2775 3425);
FORCEPROP 3 LASTPIN (-2825 3425) SIG_NAME M_D_DQS_DN<11>
J 0
(-2815 3435);
DISPLAY 0.659574 (-2815 3435);
PAINT MONO (-2815 3435);
DISPLAY INVISIBLE (-2815 3435);
FORCEPROP 1 LASTPIN (-2825 3425) BN 11
J 2
(-2773 3433);
DISPLAY 0.617021 (-2773 3433);
PAINT PINK (-2773 3433);
FORCEPROP 2 LAST CDS_LIB mstr_standard
J 0
(-2775 3425);
PAINT MONO (-2775 3425);
DISPLAY INVISIBLE (-2775 3425);
FORCEPROP 1 LAST BODY_TYPE PLUMBING
J 2
(-2775 3375);
DISPLAY 1.595745 (-2775 3375);
PAINT GREEN (-2775 3375);
DISPLAY INVISIBLE (-2775 3375);
FORCEPROP 1 LAST HDL_TAP TRUE
J 2
(-3100 3300);
DISPLAY 1.595745 (-3100 3300);
PAINT GREEN (-3100 3300);
DISPLAY INVISIBLE (-3100 3300);
FORCEPROP 1 LAST PATH I137
J 2
(-2773 3425);
DISPLAY 0.872340 (-2773 3425);
PAINT GREEN (-2773 3425);
DISPLAY INVISIBLE (-2773 3425);
FORCEADD TAP..6
R 2
(-2775 3575);
FORCEPROP 3 LASTPIN (-2825 3575) SIG_NAME M_D_DQS_DN<14>
J 0
(-2815 3585);
DISPLAY 0.659574 (-2815 3585);
PAINT MONO (-2815 3585);
DISPLAY INVISIBLE (-2815 3585);
FORCEPROP 1 LASTPIN (-2825 3575) BN 14
J 2
(-2773 3583);
DISPLAY 0.617021 (-2773 3583);
PAINT PINK (-2773 3583);
FORCEPROP 2 LAST CDS_LIB mstr_standard
J 0
(-2775 3575);
PAINT MONO (-2775 3575);
DISPLAY INVISIBLE (-2775 3575);
FORCEPROP 1 LAST BODY_TYPE PLUMBING
J 2
(-2775 3525);
DISPLAY 1.595745 (-2775 3525);
PAINT GREEN (-2775 3525);
DISPLAY INVISIBLE (-2775 3525);
FORCEPROP 1 LAST HDL_TAP TRUE
J 2
(-3100 3450);
DISPLAY 1.595745 (-3100 3450);
PAINT GREEN (-3100 3450);
DISPLAY INVISIBLE (-3100 3450);
FORCEPROP 1 LAST PATH I138
J 2
(-2773 3575);
DISPLAY 0.872340 (-2773 3575);
PAINT GREEN (-2773 3575);
DISPLAY INVISIBLE (-2773 3575);
FORCEADD TAP..6
R 2
(-2775 3625);
FORCEPROP 3 LASTPIN (-2825 3625) SIG_NAME M_D_DQS_DN<15>
J 0
(-2815 3635);
DISPLAY 0.659574 (-2815 3635);
PAINT MONO (-2815 3635);
DISPLAY INVISIBLE (-2815 3635);
FORCEPROP 1 LASTPIN (-2825 3625) BN 15
J 2
(-2773 3633);
DISPLAY 0.617021 (-2773 3633);
PAINT PINK (-2773 3633);
FORCEPROP 2 LAST CDS_LIB mstr_standard
J 0
(-2775 3625);
PAINT MONO (-2775 3625);
DISPLAY INVISIBLE (-2775 3625);
FORCEPROP 1 LAST BODY_TYPE PLUMBING
J 2
(-2775 3575);
DISPLAY 1.595745 (-2775 3575);
PAINT GREEN (-2775 3575);
DISPLAY INVISIBLE (-2775 3575);
FORCEPROP 1 LAST HDL_TAP TRUE
J 2
(-3100 3500);
DISPLAY 1.595745 (-3100 3500);
PAINT GREEN (-3100 3500);
DISPLAY INVISIBLE (-3100 3500);
FORCEPROP 1 LAST PATH I139
J 2
(-2773 3625);
DISPLAY 0.872340 (-2773 3625);
PAINT GREEN (-2773 3625);
DISPLAY INVISIBLE (-2773 3625);
FORCEADD TAP..6
(-5500 1125);
FORCEPROP 3 LASTPIN (-5450 1125) SIG_NAME M_D_ECC<1>
J 0
(-5440 1135);
DISPLAY 0.659574 (-5440 1135);
PAINT MONO (-5440 1135);
DISPLAY INVISIBLE (-5440 1135);
FORCEPROP 1 LASTPIN (-5450 1125) BN 1
J 0
(-5502 1133);
DISPLAY 0.617021 (-5502 1133);
PAINT PINK (-5502 1133);
FORCEPROP 2 LAST CDS_LIB mstr_standard
J 0
(-5500 1125);
PAINT MONO (-5500 1125);
DISPLAY INVISIBLE (-5500 1125);
FORCEPROP 1 LAST BODY_TYPE PLUMBING
J 0
(-5500 1075);
DISPLAY 1.595745 (-5500 1075);
PAINT GREEN (-5500 1075);
DISPLAY INVISIBLE (-5500 1075);
FORCEPROP 1 LAST HDL_TAP TRUE
J 0
(-5175 1000);
DISPLAY 1.595745 (-5175 1000);
PAINT GREEN (-5175 1000);
DISPLAY INVISIBLE (-5175 1000);
FORCEPROP 1 LAST PATH I14
J 0
(-5502 1125);
DISPLAY 0.872340 (-5502 1125);
PAINT GREEN (-5502 1125);
DISPLAY INVISIBLE (-5502 1125);
FORCEADD TAP..6
R 2
(-2775 3525);
FORCEPROP 3 LASTPIN (-2825 3525) SIG_NAME M_D_DQS_DN<13>
J 0
(-2815 3535);
DISPLAY 0.659574 (-2815 3535);
PAINT MONO (-2815 3535);
DISPLAY INVISIBLE (-2815 3535);
FORCEPROP 1 LASTPIN (-2825 3525) BN 13
J 2
(-2773 3533);
DISPLAY 0.617021 (-2773 3533);
PAINT PINK (-2773 3533);
FORCEPROP 2 LAST CDS_LIB mstr_standard
J 0
(-2775 3525);
PAINT MONO (-2775 3525);
DISPLAY INVISIBLE (-2775 3525);
FORCEPROP 1 LAST BODY_TYPE PLUMBING
J 2
(-2775 3475);
DISPLAY 1.595745 (-2775 3475);
PAINT GREEN (-2775 3475);
DISPLAY INVISIBLE (-2775 3475);
FORCEPROP 1 LAST HDL_TAP TRUE
J 2
(-3100 3400);
DISPLAY 1.595745 (-3100 3400);
PAINT GREEN (-3100 3400);
DISPLAY INVISIBLE (-3100 3400);
FORCEPROP 1 LAST PATH I140
J 2
(-2773 3525);
DISPLAY 0.872340 (-2773 3525);
PAINT GREEN (-2773 3525);
DISPLAY INVISIBLE (-2773 3525);
FORCEADD TAP..6
R 2
(-2775 3725);
FORCEPROP 3 LASTPIN (-2825 3725) SIG_NAME M_D_DQS_DN<17>
J 0
(-2815 3735);
DISPLAY 0.659574 (-2815 3735);
PAINT MONO (-2815 3735);
DISPLAY INVISIBLE (-2815 3735);
FORCEPROP 1 LASTPIN (-2825 3725) BN 17
J 2
(-2773 3733);
DISPLAY 0.617021 (-2773 3733);
PAINT PINK (-2773 3733);
FORCEPROP 2 LAST CDS_LIB mstr_standard
J 0
(-2775 3725);
PAINT MONO (-2775 3725);
DISPLAY INVISIBLE (-2775 3725);
FORCEPROP 1 LAST BODY_TYPE PLUMBING
J 2
(-2775 3675);
DISPLAY 1.595745 (-2775 3675);
PAINT GREEN (-2775 3675);
DISPLAY INVISIBLE (-2775 3675);
FORCEPROP 1 LAST HDL_TAP TRUE
J 2
(-3100 3600);
DISPLAY 1.595745 (-3100 3600);
PAINT GREEN (-3100 3600);
DISPLAY INVISIBLE (-3100 3600);
FORCEPROP 1 LAST PATH I141
J 2
(-2773 3725);
DISPLAY 0.872340 (-2773 3725);
PAINT GREEN (-2773 3725);
DISPLAY INVISIBLE (-2773 3725);
FORCEADD TAP..6
R 2
(-2775 3675);
FORCEPROP 3 LASTPIN (-2825 3675) SIG_NAME M_D_DQS_DN<16>
J 0
(-2815 3685);
DISPLAY 0.659574 (-2815 3685);
PAINT MONO (-2815 3685);
DISPLAY INVISIBLE (-2815 3685);
FORCEPROP 1 LASTPIN (-2825 3675) BN 16
J 2
(-2773 3683);
DISPLAY 0.617021 (-2773 3683);
PAINT PINK (-2773 3683);
FORCEPROP 2 LAST CDS_LIB mstr_standard
J 0
(-2775 3675);
PAINT MONO (-2775 3675);
DISPLAY INVISIBLE (-2775 3675);
FORCEPROP 1 LAST BODY_TYPE PLUMBING
J 2
(-2775 3625);
DISPLAY 1.595745 (-2775 3625);
PAINT GREEN (-2775 3625);
DISPLAY INVISIBLE (-2775 3625);
FORCEPROP 1 LAST HDL_TAP TRUE
J 2
(-3100 3550);
DISPLAY 1.595745 (-3100 3550);
PAINT GREEN (-3100 3550);
DISPLAY INVISIBLE (-3100 3550);
FORCEPROP 1 LAST PATH I142
J 2
(-2773 3675);
DISPLAY 0.872340 (-2773 3675);
PAINT GREEN (-2773 3675);
DISPLAY INVISIBLE (-2773 3675);
FORCEADD TAP..6
R 2
(-2775 3875);
FORCEPROP 3 LASTPIN (-2825 3875) SIG_NAME M_D_DQS_DP<1>
J 0
(-2815 3885);
DISPLAY 0.659574 (-2815 3885);
PAINT MONO (-2815 3885);
DISPLAY INVISIBLE (-2815 3885);
FORCEPROP 1 LASTPIN (-2825 3875) BN 1
J 2
(-2773 3883);
DISPLAY 0.617021 (-2773 3883);
PAINT PINK (-2773 3883);
FORCEPROP 2 LAST CDS_LIB mstr_standard
J 0
(-2775 3875);
PAINT MONO (-2775 3875);
DISPLAY INVISIBLE (-2775 3875);
FORCEPROP 1 LAST BODY_TYPE PLUMBING
J 2
(-2775 3825);
DISPLAY 1.595745 (-2775 3825);
PAINT GREEN (-2775 3825);
DISPLAY INVISIBLE (-2775 3825);
FORCEPROP 1 LAST HDL_TAP TRUE
J 2
(-3100 3750);
DISPLAY 1.595745 (-3100 3750);
PAINT GREEN (-3100 3750);
DISPLAY INVISIBLE (-3100 3750);
FORCEPROP 1 LAST PATH I143
J 2
(-2773 3875);
DISPLAY 0.872340 (-2773 3875);
PAINT GREEN (-2773 3875);
DISPLAY INVISIBLE (-2773 3875);
FORCEADD TAP..6
R 2
(-2775 3825);
FORCEPROP 3 LASTPIN (-2825 3825) SIG_NAME M_D_DQS_DP<0>
J 0
(-2815 3835);
DISPLAY 0.659574 (-2815 3835);
PAINT MONO (-2815 3835);
DISPLAY INVISIBLE (-2815 3835);
FORCEPROP 1 LASTPIN (-2825 3825) BN 0
J 2
(-2773 3833);
DISPLAY 0.617021 (-2773 3833);
PAINT PINK (-2773 3833);
FORCEPROP 2 LAST CDS_LIB mstr_standard
J 0
(-2775 3825);
PAINT MONO (-2775 3825);
DISPLAY INVISIBLE (-2775 3825);
FORCEPROP 1 LAST BODY_TYPE PLUMBING
J 2
(-2775 3775);
DISPLAY 1.595745 (-2775 3775);
PAINT GREEN (-2775 3775);
DISPLAY INVISIBLE (-2775 3775);
FORCEPROP 1 LAST HDL_TAP TRUE
J 2
(-3100 3700);
DISPLAY 1.595745 (-3100 3700);
PAINT GREEN (-3100 3700);
DISPLAY INVISIBLE (-3100 3700);
FORCEPROP 1 LAST PATH I144
J 2
(-2773 3825);
DISPLAY 0.872340 (-2773 3825);
PAINT GREEN (-2773 3825);
DISPLAY INVISIBLE (-2773 3825);
FORCEADD TAP..6
R 2
(-2775 3925);
FORCEPROP 3 LASTPIN (-2825 3925) SIG_NAME M_D_DQS_DP<2>
J 0
(-2815 3935);
DISPLAY 0.659574 (-2815 3935);
PAINT MONO (-2815 3935);
DISPLAY INVISIBLE (-2815 3935);
FORCEPROP 1 LASTPIN (-2825 3925) BN 2
J 2
(-2773 3933);
DISPLAY 0.617021 (-2773 3933);
PAINT PINK (-2773 3933);
FORCEPROP 2 LAST CDS_LIB mstr_standard
J 0
(-2775 3925);
PAINT MONO (-2775 3925);
DISPLAY INVISIBLE (-2775 3925);
FORCEPROP 1 LAST BODY_TYPE PLUMBING
J 2
(-2775 3875);
DISPLAY 1.595745 (-2775 3875);
PAINT GREEN (-2775 3875);
DISPLAY INVISIBLE (-2775 3875);
FORCEPROP 1 LAST HDL_TAP TRUE
J 2
(-3100 3800);
DISPLAY 1.595745 (-3100 3800);
PAINT GREEN (-3100 3800);
DISPLAY INVISIBLE (-3100 3800);
FORCEPROP 1 LAST PATH I145
J 2
(-2773 3925);
DISPLAY 0.872340 (-2773 3925);
PAINT GREEN (-2773 3925);
DISPLAY INVISIBLE (-2773 3925);
FORCEADD TAP..6
R 2
(-2775 3975);
FORCEPROP 3 LASTPIN (-2825 3975) SIG_NAME M_D_DQS_DP<3>
J 0
(-2815 3985);
DISPLAY 0.659574 (-2815 3985);
PAINT MONO (-2815 3985);
DISPLAY INVISIBLE (-2815 3985);
FORCEPROP 1 LASTPIN (-2825 3975) BN 3
J 2
(-2773 3983);
DISPLAY 0.617021 (-2773 3983);
PAINT PINK (-2773 3983);
FORCEPROP 2 LAST CDS_LIB mstr_standard
J 0
(-2775 3975);
PAINT MONO (-2775 3975);
DISPLAY INVISIBLE (-2775 3975);
FORCEPROP 1 LAST BODY_TYPE PLUMBING
J 2
(-2775 3925);
DISPLAY 1.595745 (-2775 3925);
PAINT GREEN (-2775 3925);
DISPLAY INVISIBLE (-2775 3925);
FORCEPROP 1 LAST HDL_TAP TRUE
J 2
(-3100 3850);
DISPLAY 1.595745 (-3100 3850);
PAINT GREEN (-3100 3850);
DISPLAY INVISIBLE (-3100 3850);
FORCEPROP 1 LAST PATH I146
J 2
(-2773 3975);
DISPLAY 0.872340 (-2773 3975);
PAINT GREEN (-2773 3975);
DISPLAY INVISIBLE (-2773 3975);
FORCEADD OFFPAGE..2
(-1925 525);
FORCEPROP 2 LAST $XR0 49 
J 0
(-1736 525);
DISPLAY 0.638298 (-1736 525);
PAINT MONO (-1736 525);
FORCEPROP 2 LAST $XR1 50 
J 0
(-1646 525);
DISPLAY 0.638298 (-1646 525);
PAINT MONO (-1646 525);
FORCEPROP 2 LAST CDS_LIB mstr_standard
J 0
(-1925 525);
PAINT MONO (-1925 525);
DISPLAY INVISIBLE (-1925 525);
FORCEPROP 1 LAST OFFPAGE TRUE
J 0
(-1600 400);
DISPLAY 1.170213 (-1600 400);
PAINT GREEN (-1600 400);
DISPLAY INVISIBLE (-1600 400);
FORCEPROP 1 LAST COMMENT_BODY TRUE
J 0
(-1970 430);
DISPLAY 1.170213 (-1970 430);
PAINT GREEN (-1970 430);
DISPLAY INVISIBLE (-1970 430);
FORCEPROP 2 LAST PATH I147
J 0
(-1750 600);
DISPLAY 1.021277 (-1750 600);
PAINT ORANGE (-1750 600);
DISPLAY INVISIBLE (-1750 600);
FORCEADD OFFPAGE..4
(-1925 575);
FORCEPROP 2 LAST $XR0 49 
J 0
(-1739 575);
DISPLAY 0.638298 (-1739 575);
PAINT MONO (-1739 575);
FORCEPROP 2 LAST $XR1 50 
J 0
(-1649 575);
DISPLAY 0.638298 (-1649 575);
PAINT MONO (-1649 575);
FORCEPROP 2 LAST CDS_LIB mstr_standard
J 0
(-1925 575);
PAINT MONO (-1925 575);
DISPLAY INVISIBLE (-1925 575);
FORCEPROP 1 LAST OFFPAGE TRUE
J 0
(-1600 450);
DISPLAY 1.170213 (-1600 450);
PAINT GREEN (-1600 450);
DISPLAY INVISIBLE (-1600 450);
FORCEPROP 1 LAST COMMENT_BODY TRUE
J 0
(-1950 475);
DISPLAY 1.170213 (-1950 475);
PAINT GREEN (-1950 475);
DISPLAY INVISIBLE (-1950 475);
FORCEPROP 2 LAST PATH I148
J 0
(-1750 650);
DISPLAY 1.021277 (-1750 650);
PAINT ORANGE (-1750 650);
DISPLAY INVISIBLE (-1750 650);
FORCEADD OFFPAGE..2
(-1925 625);
FORCEPROP 2 LAST $XR0 49 
J 0
(-1736 625);
DISPLAY 0.638298 (-1736 625);
PAINT MONO (-1736 625);
FORCEPROP 2 LAST $XR1 50 
J 0
(-1646 625);
DISPLAY 0.638298 (-1646 625);
PAINT MONO (-1646 625);
FORCEPROP 2 LAST CDS_LIB mstr_standard
J 0
(-1925 625);
PAINT MONO (-1925 625);
DISPLAY INVISIBLE (-1925 625);
FORCEPROP 1 LAST OFFPAGE TRUE
J 0
(-1600 500);
DISPLAY 1.170213 (-1600 500);
PAINT GREEN (-1600 500);
DISPLAY INVISIBLE (-1600 500);
FORCEPROP 1 LAST COMMENT_BODY TRUE
J 0
(-1970 530);
DISPLAY 1.170213 (-1970 530);
PAINT GREEN (-1970 530);
DISPLAY INVISIBLE (-1970 530);
FORCEPROP 2 LAST PATH I149
J 0
(-1750 700);
DISPLAY 1.021277 (-1750 700);
PAINT ORANGE (-1750 700);
DISPLAY INVISIBLE (-1750 700);
FORCEADD TAP..6
(-5500 1175);
FORCEPROP 3 LASTPIN (-5450 1175) SIG_NAME M_D_ECC<2>
J 0
(-5440 1185);
DISPLAY 0.659574 (-5440 1185);
PAINT MONO (-5440 1185);
DISPLAY INVISIBLE (-5440 1185);
FORCEPROP 1 LASTPIN (-5450 1175) BN 2
J 0
(-5502 1183);
DISPLAY 0.617021 (-5502 1183);
PAINT PINK (-5502 1183);
FORCEPROP 2 LAST CDS_LIB mstr_standard
J 0
(-5500 1175);
PAINT MONO (-5500 1175);
DISPLAY INVISIBLE (-5500 1175);
FORCEPROP 1 LAST BODY_TYPE PLUMBING
J 0
(-5500 1125);
DISPLAY 1.595745 (-5500 1125);
PAINT GREEN (-5500 1125);
DISPLAY INVISIBLE (-5500 1125);
FORCEPROP 1 LAST HDL_TAP TRUE
J 0
(-5175 1050);
DISPLAY 1.595745 (-5175 1050);
PAINT GREEN (-5175 1050);
DISPLAY INVISIBLE (-5175 1050);
FORCEPROP 1 LAST PATH I15
J 0
(-5502 1175);
DISPLAY 0.872340 (-5502 1175);
PAINT GREEN (-5502 1175);
DISPLAY INVISIBLE (-5502 1175);
FORCEADD OFFPAGE..2
(-1925 825);
FORCEPROP 2 LAST $XR0 49 
J 0
(-1736 825);
DISPLAY 0.638298 (-1736 825);
PAINT MONO (-1736 825);
FORCEPROP 2 LAST $XR1 50 
J 0
(-1646 825);
DISPLAY 0.638298 (-1646 825);
PAINT MONO (-1646 825);
FORCEPROP 2 LAST CDS_LIB mstr_standard
J 0
(-1925 825);
PAINT MONO (-1925 825);
DISPLAY INVISIBLE (-1925 825);
FORCEPROP 1 LAST OFFPAGE TRUE
J 0
(-1600 700);
DISPLAY 1.170213 (-1600 700);
PAINT GREEN (-1600 700);
DISPLAY INVISIBLE (-1600 700);
FORCEPROP 1 LAST COMMENT_BODY TRUE
J 0
(-1970 730);
DISPLAY 1.170213 (-1970 730);
PAINT GREEN (-1970 730);
DISPLAY INVISIBLE (-1970 730);
FORCEPROP 2 LAST PATH I150
J 0
(-1750 900);
DISPLAY 1.021277 (-1750 900);
PAINT ORANGE (-1750 900);
DISPLAY INVISIBLE (-1750 900);
FORCEADD OFFPAGE..2
(-1925 925);
FORCEPROP 2 LAST $XR0 49 
J 0
(-1736 925);
DISPLAY 0.638298 (-1736 925);
PAINT MONO (-1736 925);
FORCEPROP 2 LAST $XR1 50 
J 0
(-1646 925);
DISPLAY 0.638298 (-1646 925);
PAINT MONO (-1646 925);
FORCEPROP 2 LAST CDS_LIB mstr_standard
J 0
(-1925 925);
PAINT MONO (-1925 925);
DISPLAY INVISIBLE (-1925 925);
FORCEPROP 1 LAST OFFPAGE TRUE
J 0
(-1600 800);
DISPLAY 1.170213 (-1600 800);
PAINT GREEN (-1600 800);
DISPLAY INVISIBLE (-1600 800);
FORCEPROP 1 LAST COMMENT_BODY TRUE
J 0
(-1970 830);
DISPLAY 1.170213 (-1970 830);
PAINT GREEN (-1970 830);
DISPLAY INVISIBLE (-1970 830);
FORCEPROP 2 LAST PATH I151
J 0
(-1750 1000);
DISPLAY 1.021277 (-1750 1000);
PAINT ORANGE (-1750 1000);
DISPLAY INVISIBLE (-1750 1000);
FORCEADD OFFPAGE..2
(-1925 1375);
FORCEPROP 2 LAST $XR0 49 
J 0
(-1736 1375);
DISPLAY 0.638298 (-1736 1375);
PAINT MONO (-1736 1375);
FORCEPROP 2 LAST $XR1 50 
J 0
(-1646 1375);
DISPLAY 0.638298 (-1646 1375);
PAINT MONO (-1646 1375);
FORCEPROP 2 LAST CDS_LIB mstr_standard
J 0
(-1925 1375);
PAINT MONO (-1925 1375);
DISPLAY INVISIBLE (-1925 1375);
FORCEPROP 1 LAST OFFPAGE TRUE
J 0
(-1600 1250);
DISPLAY 1.170213 (-1600 1250);
PAINT GREEN (-1600 1250);
DISPLAY INVISIBLE (-1600 1250);
FORCEPROP 1 LAST COMMENT_BODY TRUE
J 0
(-1970 1280);
DISPLAY 1.170213 (-1970 1280);
PAINT GREEN (-1970 1280);
DISPLAY INVISIBLE (-1970 1280);
FORCEPROP 2 LAST PATH I152
J 0
(-1750 1450);
DISPLAY 1.021277 (-1750 1450);
PAINT ORANGE (-1750 1450);
DISPLAY INVISIBLE (-1750 1450);
FORCEADD OFFPAGE..2
(-1925 1625);
FORCEPROP 2 LAST $XR0 49 
J 0
(-1736 1625);
DISPLAY 0.638298 (-1736 1625);
PAINT MONO (-1736 1625);
FORCEPROP 2 LAST $XR1 50 
J 0
(-1646 1625);
DISPLAY 0.638298 (-1646 1625);
PAINT MONO (-1646 1625);
FORCEPROP 2 LAST CDS_LIB mstr_standard
J 0
(-1925 1625);
PAINT MONO (-1925 1625);
DISPLAY INVISIBLE (-1925 1625);
FORCEPROP 1 LAST OFFPAGE TRUE
J 0
(-1600 1500);
DISPLAY 1.170213 (-1600 1500);
PAINT GREEN (-1600 1500);
DISPLAY INVISIBLE (-1600 1500);
FORCEPROP 1 LAST COMMENT_BODY TRUE
J 0
(-1970 1530);
DISPLAY 1.170213 (-1970 1530);
PAINT GREEN (-1970 1530);
DISPLAY INVISIBLE (-1970 1530);
FORCEPROP 2 LAST PATH I153
J 0
(-1750 1700);
DISPLAY 1.021277 (-1750 1700);
PAINT ORANGE (-1750 1700);
DISPLAY INVISIBLE (-1750 1700);
FORCEADD OFFPAGE..2
(-1925 1875);
FORCEPROP 2 LAST $XR0 49 
J 0
(-1736 1875);
DISPLAY 0.638298 (-1736 1875);
PAINT MONO (-1736 1875);
FORCEPROP 2 LAST $XR1 50 
J 0
(-1646 1875);
DISPLAY 0.638298 (-1646 1875);
PAINT MONO (-1646 1875);
FORCEPROP 2 LAST CDS_LIB mstr_standard
J 0
(-1925 1875);
PAINT MONO (-1925 1875);
DISPLAY INVISIBLE (-1925 1875);
FORCEPROP 1 LAST OFFPAGE TRUE
J 0
(-1600 1750);
DISPLAY 1.170213 (-1600 1750);
PAINT GREEN (-1600 1750);
DISPLAY INVISIBLE (-1600 1750);
FORCEPROP 1 LAST COMMENT_BODY TRUE
J 0
(-1970 1780);
DISPLAY 1.170213 (-1970 1780);
PAINT GREEN (-1970 1780);
DISPLAY INVISIBLE (-1970 1780);
FORCEPROP 2 LAST PATH I154
J 0
(-1750 1950);
DISPLAY 1.021277 (-1750 1950);
PAINT ORANGE (-1750 1950);
DISPLAY INVISIBLE (-1750 1950);
FORCEADD OFFPAGE..2
(-1925 2825);
FORCEPROP 2 LAST $XR0 49 
J 0
(-1736 2825);
DISPLAY 0.638298 (-1736 2825);
PAINT MONO (-1736 2825);
FORCEPROP 2 LAST $XR1 50 
J 0
(-1646 2825);
DISPLAY 0.638298 (-1646 2825);
PAINT MONO (-1646 2825);
FORCEPROP 2 LAST CDS_LIB mstr_standard
J 0
(-1925 2825);
PAINT MONO (-1925 2825);
DISPLAY INVISIBLE (-1925 2825);
FORCEPROP 1 LAST OFFPAGE TRUE
J 0
(-1600 2700);
DISPLAY 1.170213 (-1600 2700);
PAINT GREEN (-1600 2700);
DISPLAY INVISIBLE (-1600 2700);
FORCEPROP 1 LAST COMMENT_BODY TRUE
J 0
(-1970 2730);
DISPLAY 1.170213 (-1970 2730);
PAINT GREEN (-1970 2730);
DISPLAY INVISIBLE (-1970 2730);
FORCEPROP 2 LAST PATH I155
J 0
(-1750 2900);
DISPLAY 1.021277 (-1750 2900);
PAINT ORANGE (-1750 2900);
DISPLAY INVISIBLE (-1750 2900);
FORCEADD OFFPAGE..3
(-1925 3775);
FORCEPROP 2 LAST $XR0 49 
J 0
(-1711 3775);
DISPLAY 0.638298 (-1711 3775);
PAINT MONO (-1711 3775);
FORCEPROP 2 LAST $XR1 50 
J 0
(-1621 3775);
DISPLAY 0.638298 (-1621 3775);
PAINT MONO (-1621 3775);
FORCEPROP 2 LAST CDS_LIB mstr_standard
J 0
(-1925 3775);
PAINT MONO (-1925 3775);
DISPLAY INVISIBLE (-1925 3775);
FORCEPROP 1 LAST OFFPAGE TRUE
J 0
(-1600 3650);
DISPLAY 1.170213 (-1600 3650);
PAINT GREEN (-1600 3650);
DISPLAY INVISIBLE (-1600 3650);
FORCEPROP 1 LAST COMMENT_BODY TRUE
J 0
(-1975 3675);
DISPLAY 1.170213 (-1975 3675);
PAINT GREEN (-1975 3675);
DISPLAY INVISIBLE (-1975 3675);
FORCEPROP 2 LAST PATH I156
J 0
(-1725 3850);
DISPLAY 1.021277 (-1725 3850);
PAINT ORANGE (-1725 3850);
DISPLAY INVISIBLE (-1725 3850);
FORCEADD TAP..6
R 2
(-2775 4025);
FORCEPROP 3 LASTPIN (-2825 4025) SIG_NAME M_D_DQS_DP<4>
J 0
(-2815 4035);
DISPLAY 0.659574 (-2815 4035);
PAINT MONO (-2815 4035);
DISPLAY INVISIBLE (-2815 4035);
FORCEPROP 1 LASTPIN (-2825 4025) BN 4
J 2
(-2773 4033);
DISPLAY 0.617021 (-2773 4033);
PAINT PINK (-2773 4033);
FORCEPROP 2 LAST CDS_LIB mstr_standard
J 0
(-2775 4025);
PAINT MONO (-2775 4025);
DISPLAY INVISIBLE (-2775 4025);
FORCEPROP 1 LAST BODY_TYPE PLUMBING
J 2
(-2775 3975);
DISPLAY 1.595745 (-2775 3975);
PAINT GREEN (-2775 3975);
DISPLAY INVISIBLE (-2775 3975);
FORCEPROP 1 LAST HDL_TAP TRUE
J 2
(-3100 3900);
DISPLAY 1.595745 (-3100 3900);
PAINT GREEN (-3100 3900);
DISPLAY INVISIBLE (-3100 3900);
FORCEPROP 1 LAST PATH I157
J 2
(-2773 4025);
DISPLAY 0.872340 (-2773 4025);
PAINT GREEN (-2773 4025);
DISPLAY INVISIBLE (-2773 4025);
FORCEADD TAP..6
R 2
(-2775 4125);
FORCEPROP 3 LASTPIN (-2825 4125) SIG_NAME M_D_DQS_DP<6>
J 0
(-2815 4135);
DISPLAY 0.659574 (-2815 4135);
PAINT MONO (-2815 4135);
DISPLAY INVISIBLE (-2815 4135);
FORCEPROP 1 LASTPIN (-2825 4125) BN 6
J 2
(-2773 4133);
DISPLAY 0.617021 (-2773 4133);
PAINT PINK (-2773 4133);
FORCEPROP 2 LAST CDS_LIB mstr_standard
J 0
(-2775 4125);
PAINT MONO (-2775 4125);
DISPLAY INVISIBLE (-2775 4125);
FORCEPROP 1 LAST BODY_TYPE PLUMBING
J 2
(-2775 4075);
DISPLAY 1.595745 (-2775 4075);
PAINT GREEN (-2775 4075);
DISPLAY INVISIBLE (-2775 4075);
FORCEPROP 1 LAST HDL_TAP TRUE
J 2
(-3100 4000);
DISPLAY 1.595745 (-3100 4000);
PAINT GREEN (-3100 4000);
DISPLAY INVISIBLE (-3100 4000);
FORCEPROP 1 LAST PATH I158
J 2
(-2773 4125);
DISPLAY 0.872340 (-2773 4125);
PAINT GREEN (-2773 4125);
DISPLAY INVISIBLE (-2773 4125);
FORCEADD TAP..6
R 2
(-2775 4075);
FORCEPROP 3 LASTPIN (-2825 4075) SIG_NAME M_D_DQS_DP<5>
J 0
(-2815 4085);
DISPLAY 0.659574 (-2815 4085);
PAINT MONO (-2815 4085);
DISPLAY INVISIBLE (-2815 4085);
FORCEPROP 1 LASTPIN (-2825 4075) BN 5
J 2
(-2773 4083);
DISPLAY 0.617021 (-2773 4083);
PAINT PINK (-2773 4083);
FORCEPROP 2 LAST CDS_LIB mstr_standard
J 0
(-2775 4075);
PAINT MONO (-2775 4075);
DISPLAY INVISIBLE (-2775 4075);
FORCEPROP 1 LAST BODY_TYPE PLUMBING
J 2
(-2775 4025);
DISPLAY 1.595745 (-2775 4025);
PAINT GREEN (-2775 4025);
DISPLAY INVISIBLE (-2775 4025);
FORCEPROP 1 LAST HDL_TAP TRUE
J 2
(-3100 3950);
DISPLAY 1.595745 (-3100 3950);
PAINT GREEN (-3100 3950);
DISPLAY INVISIBLE (-3100 3950);
FORCEPROP 1 LAST PATH I159
J 2
(-2773 4075);
DISPLAY 0.872340 (-2773 4075);
PAINT GREEN (-2773 4075);
DISPLAY INVISIBLE (-2773 4075);
FORCEADD TAP..6
(-5500 1275);
FORCEPROP 3 LASTPIN (-5450 1275) SIG_NAME M_D_ECC<4>
J 0
(-5440 1285);
DISPLAY 0.659574 (-5440 1285);
PAINT MONO (-5440 1285);
DISPLAY INVISIBLE (-5440 1285);
FORCEPROP 1 LASTPIN (-5450 1275) BN 4
J 0
(-5502 1283);
DISPLAY 0.617021 (-5502 1283);
PAINT PINK (-5502 1283);
FORCEPROP 2 LAST CDS_LIB mstr_standard
J 0
(-5500 1275);
PAINT MONO (-5500 1275);
DISPLAY INVISIBLE (-5500 1275);
FORCEPROP 1 LAST BODY_TYPE PLUMBING
J 0
(-5500 1225);
DISPLAY 1.595745 (-5500 1225);
PAINT GREEN (-5500 1225);
DISPLAY INVISIBLE (-5500 1225);
FORCEPROP 1 LAST HDL_TAP TRUE
J 0
(-5175 1150);
DISPLAY 1.595745 (-5175 1150);
PAINT GREEN (-5175 1150);
DISPLAY INVISIBLE (-5175 1150);
FORCEPROP 1 LAST PATH I16
J 0
(-5502 1275);
DISPLAY 0.872340 (-5502 1275);
PAINT GREEN (-5502 1275);
DISPLAY INVISIBLE (-5502 1275);
FORCEADD TAP..6
R 2
(-2775 4175);
FORCEPROP 3 LASTPIN (-2825 4175) SIG_NAME M_D_DQS_DP<7>
J 0
(-2815 4185);
DISPLAY 0.659574 (-2815 4185);
PAINT MONO (-2815 4185);
DISPLAY INVISIBLE (-2815 4185);
FORCEPROP 1 LASTPIN (-2825 4175) BN 7
J 2
(-2773 4183);
DISPLAY 0.617021 (-2773 4183);
PAINT PINK (-2773 4183);
FORCEPROP 2 LAST CDS_LIB mstr_standard
J 0
(-2775 4175);
PAINT MONO (-2775 4175);
DISPLAY INVISIBLE (-2775 4175);
FORCEPROP 1 LAST BODY_TYPE PLUMBING
J 2
(-2775 4125);
DISPLAY 1.595745 (-2775 4125);
PAINT GREEN (-2775 4125);
DISPLAY INVISIBLE (-2775 4125);
FORCEPROP 1 LAST HDL_TAP TRUE
J 2
(-3100 4050);
DISPLAY 1.595745 (-3100 4050);
PAINT GREEN (-3100 4050);
DISPLAY INVISIBLE (-3100 4050);
FORCEPROP 1 LAST PATH I160
J 2
(-2773 4175);
DISPLAY 0.872340 (-2773 4175);
PAINT GREEN (-2773 4175);
DISPLAY INVISIBLE (-2773 4175);
FORCEADD TAP..6
R 2
(-2775 4275);
FORCEPROP 3 LASTPIN (-2825 4275) SIG_NAME M_D_DQS_DP<9>
J 0
(-2815 4285);
DISPLAY 0.659574 (-2815 4285);
PAINT MONO (-2815 4285);
DISPLAY INVISIBLE (-2815 4285);
FORCEPROP 1 LASTPIN (-2825 4275) BN 9
J 2
(-2773 4283);
DISPLAY 0.617021 (-2773 4283);
PAINT PINK (-2773 4283);
FORCEPROP 2 LAST CDS_LIB mstr_standard
J 0
(-2775 4275);
PAINT MONO (-2775 4275);
DISPLAY INVISIBLE (-2775 4275);
FORCEPROP 1 LAST BODY_TYPE PLUMBING
J 2
(-2775 4225);
DISPLAY 1.595745 (-2775 4225);
PAINT GREEN (-2775 4225);
DISPLAY INVISIBLE (-2775 4225);
FORCEPROP 1 LAST HDL_TAP TRUE
J 2
(-3100 4150);
DISPLAY 1.595745 (-3100 4150);
PAINT GREEN (-3100 4150);
DISPLAY INVISIBLE (-3100 4150);
FORCEPROP 1 LAST PATH I161
J 2
(-2773 4275);
DISPLAY 0.872340 (-2773 4275);
PAINT GREEN (-2773 4275);
DISPLAY INVISIBLE (-2773 4275);
FORCEADD TAP..6
R 2
(-2775 4225);
FORCEPROP 3 LASTPIN (-2825 4225) SIG_NAME M_D_DQS_DP<8>
J 0
(-2815 4235);
DISPLAY 0.659574 (-2815 4235);
PAINT MONO (-2815 4235);
DISPLAY INVISIBLE (-2815 4235);
FORCEPROP 1 LASTPIN (-2825 4225) BN 8
J 2
(-2773 4233);
DISPLAY 0.617021 (-2773 4233);
PAINT PINK (-2773 4233);
FORCEPROP 2 LAST CDS_LIB mstr_standard
J 0
(-2775 4225);
PAINT MONO (-2775 4225);
DISPLAY INVISIBLE (-2775 4225);
FORCEPROP 1 LAST BODY_TYPE PLUMBING
J 2
(-2775 4175);
DISPLAY 1.595745 (-2775 4175);
PAINT GREEN (-2775 4175);
DISPLAY INVISIBLE (-2775 4175);
FORCEPROP 1 LAST HDL_TAP TRUE
J 2
(-3100 4100);
DISPLAY 1.595745 (-3100 4100);
PAINT GREEN (-3100 4100);
DISPLAY INVISIBLE (-3100 4100);
FORCEPROP 1 LAST PATH I162
J 2
(-2773 4225);
DISPLAY 0.872340 (-2773 4225);
PAINT GREEN (-2773 4225);
DISPLAY INVISIBLE (-2773 4225);
FORCEADD TAP..6
R 2
(-2775 4325);
FORCEPROP 3 LASTPIN (-2825 4325) SIG_NAME M_D_DQS_DP<10>
J 0
(-2815 4335);
DISPLAY 0.659574 (-2815 4335);
PAINT MONO (-2815 4335);
DISPLAY INVISIBLE (-2815 4335);
FORCEPROP 1 LASTPIN (-2825 4325) BN 10
J 2
(-2773 4333);
DISPLAY 0.617021 (-2773 4333);
PAINT PINK (-2773 4333);
FORCEPROP 2 LAST CDS_LIB mstr_standard
J 0
(-2775 4325);
PAINT MONO (-2775 4325);
DISPLAY INVISIBLE (-2775 4325);
FORCEPROP 1 LAST BODY_TYPE PLUMBING
J 2
(-2775 4275);
DISPLAY 1.595745 (-2775 4275);
PAINT GREEN (-2775 4275);
DISPLAY INVISIBLE (-2775 4275);
FORCEPROP 1 LAST HDL_TAP TRUE
J 2
(-3100 4200);
DISPLAY 1.595745 (-3100 4200);
PAINT GREEN (-3100 4200);
DISPLAY INVISIBLE (-3100 4200);
FORCEPROP 1 LAST PATH I163
J 2
(-2773 4325);
DISPLAY 0.872340 (-2773 4325);
PAINT GREEN (-2773 4325);
DISPLAY INVISIBLE (-2773 4325);
FORCEADD TAP..6
R 2
(-2775 4375);
FORCEPROP 3 LASTPIN (-2825 4375) SIG_NAME M_D_DQS_DP<11>
J 0
(-2815 4385);
DISPLAY 0.659574 (-2815 4385);
PAINT MONO (-2815 4385);
DISPLAY INVISIBLE (-2815 4385);
FORCEPROP 1 LASTPIN (-2825 4375) BN 11
J 2
(-2773 4383);
DISPLAY 0.617021 (-2773 4383);
PAINT PINK (-2773 4383);
FORCEPROP 2 LAST CDS_LIB mstr_standard
J 0
(-2775 4375);
PAINT MONO (-2775 4375);
DISPLAY INVISIBLE (-2775 4375);
FORCEPROP 1 LAST BODY_TYPE PLUMBING
J 2
(-2775 4325);
DISPLAY 1.595745 (-2775 4325);
PAINT GREEN (-2775 4325);
DISPLAY INVISIBLE (-2775 4325);
FORCEPROP 1 LAST HDL_TAP TRUE
J 2
(-3100 4250);
DISPLAY 1.595745 (-3100 4250);
PAINT GREEN (-3100 4250);
DISPLAY INVISIBLE (-3100 4250);
FORCEPROP 1 LAST PATH I164
J 2
(-2773 4375);
DISPLAY 0.872340 (-2773 4375);
PAINT GREEN (-2773 4375);
DISPLAY INVISIBLE (-2773 4375);
FORCEADD TAP..6
R 2
(-2775 4425);
FORCEPROP 3 LASTPIN (-2825 4425) SIG_NAME M_D_DQS_DP<12>
J 0
(-2815 4435);
DISPLAY 0.659574 (-2815 4435);
PAINT MONO (-2815 4435);
DISPLAY INVISIBLE (-2815 4435);
FORCEPROP 1 LASTPIN (-2825 4425) BN 12
J 2
(-2773 4433);
DISPLAY 0.617021 (-2773 4433);
PAINT PINK (-2773 4433);
FORCEPROP 2 LAST CDS_LIB mstr_standard
J 0
(-2775 4425);
PAINT MONO (-2775 4425);
DISPLAY INVISIBLE (-2775 4425);
FORCEPROP 1 LAST BODY_TYPE PLUMBING
J 2
(-2775 4375);
DISPLAY 1.595745 (-2775 4375);
PAINT GREEN (-2775 4375);
DISPLAY INVISIBLE (-2775 4375);
FORCEPROP 1 LAST HDL_TAP TRUE
J 2
(-3100 4300);
DISPLAY 1.595745 (-3100 4300);
PAINT GREEN (-3100 4300);
DISPLAY INVISIBLE (-3100 4300);
FORCEPROP 1 LAST PATH I165
J 2
(-2773 4425);
DISPLAY 0.872340 (-2773 4425);
PAINT GREEN (-2773 4425);
DISPLAY INVISIBLE (-2773 4425);
FORCEADD TAP..6
R 2
(-2775 4525);
FORCEPROP 3 LASTPIN (-2825 4525) SIG_NAME M_D_DQS_DP<14>
J 0
(-2815 4535);
DISPLAY 0.659574 (-2815 4535);
PAINT MONO (-2815 4535);
DISPLAY INVISIBLE (-2815 4535);
FORCEPROP 1 LASTPIN (-2825 4525) BN 14
J 2
(-2773 4533);
DISPLAY 0.617021 (-2773 4533);
PAINT PINK (-2773 4533);
FORCEPROP 2 LAST CDS_LIB mstr_standard
J 0
(-2775 4525);
PAINT MONO (-2775 4525);
DISPLAY INVISIBLE (-2775 4525);
FORCEPROP 1 LAST BODY_TYPE PLUMBING
J 2
(-2775 4475);
DISPLAY 1.595745 (-2775 4475);
PAINT GREEN (-2775 4475);
DISPLAY INVISIBLE (-2775 4475);
FORCEPROP 1 LAST HDL_TAP TRUE
J 2
(-3100 4400);
DISPLAY 1.595745 (-3100 4400);
PAINT GREEN (-3100 4400);
DISPLAY INVISIBLE (-3100 4400);
FORCEPROP 1 LAST PATH I166
J 2
(-2773 4525);
DISPLAY 0.872340 (-2773 4525);
PAINT GREEN (-2773 4525);
DISPLAY INVISIBLE (-2773 4525);
FORCEADD TAP..6
R 2
(-2775 4475);
FORCEPROP 3 LASTPIN (-2825 4475) SIG_NAME M_D_DQS_DP<13>
J 0
(-2815 4485);
DISPLAY 0.659574 (-2815 4485);
PAINT MONO (-2815 4485);
DISPLAY INVISIBLE (-2815 4485);
FORCEPROP 1 LASTPIN (-2825 4475) BN 13
J 2
(-2773 4483);
DISPLAY 0.617021 (-2773 4483);
PAINT PINK (-2773 4483);
FORCEPROP 2 LAST CDS_LIB mstr_standard
J 0
(-2775 4475);
PAINT MONO (-2775 4475);
DISPLAY INVISIBLE (-2775 4475);
FORCEPROP 1 LAST BODY_TYPE PLUMBING
J 2
(-2775 4425);
DISPLAY 1.595745 (-2775 4425);
PAINT GREEN (-2775 4425);
DISPLAY INVISIBLE (-2775 4425);
FORCEPROP 1 LAST HDL_TAP TRUE
J 2
(-3100 4350);
DISPLAY 1.595745 (-3100 4350);
PAINT GREEN (-3100 4350);
DISPLAY INVISIBLE (-3100 4350);
FORCEPROP 1 LAST PATH I167
J 2
(-2773 4475);
DISPLAY 0.872340 (-2773 4475);
PAINT GREEN (-2773 4475);
DISPLAY INVISIBLE (-2773 4475);
FORCEADD TAP..6
R 2
(-2775 4625);
FORCEPROP 3 LASTPIN (-2825 4625) SIG_NAME M_D_DQS_DP<16>
J 0
(-2815 4635);
DISPLAY 0.659574 (-2815 4635);
PAINT MONO (-2815 4635);
DISPLAY INVISIBLE (-2815 4635);
FORCEPROP 1 LASTPIN (-2825 4625) BN 16
J 2
(-2773 4633);
DISPLAY 0.617021 (-2773 4633);
PAINT PINK (-2773 4633);
FORCEPROP 2 LAST CDS_LIB mstr_standard
J 0
(-2775 4625);
PAINT MONO (-2775 4625);
DISPLAY INVISIBLE (-2775 4625);
FORCEPROP 1 LAST BODY_TYPE PLUMBING
J 2
(-2775 4575);
DISPLAY 1.595745 (-2775 4575);
PAINT GREEN (-2775 4575);
DISPLAY INVISIBLE (-2775 4575);
FORCEPROP 1 LAST HDL_TAP TRUE
J 2
(-3100 4500);
DISPLAY 1.595745 (-3100 4500);
PAINT GREEN (-3100 4500);
DISPLAY INVISIBLE (-3100 4500);
FORCEPROP 1 LAST PATH I168
J 2
(-2773 4625);
DISPLAY 0.872340 (-2773 4625);
PAINT GREEN (-2773 4625);
DISPLAY INVISIBLE (-2773 4625);
FORCEADD TAP..6
R 2
(-2775 4575);
FORCEPROP 3 LASTPIN (-2825 4575) SIG_NAME M_D_DQS_DP<15>
J 0
(-2815 4585);
DISPLAY 0.659574 (-2815 4585);
PAINT MONO (-2815 4585);
DISPLAY INVISIBLE (-2815 4585);
FORCEPROP 1 LASTPIN (-2825 4575) BN 15
J 2
(-2773 4583);
DISPLAY 0.617021 (-2773 4583);
PAINT PINK (-2773 4583);
FORCEPROP 2 LAST CDS_LIB mstr_standard
J 0
(-2775 4575);
PAINT MONO (-2775 4575);
DISPLAY INVISIBLE (-2775 4575);
FORCEPROP 1 LAST BODY_TYPE PLUMBING
J 2
(-2775 4525);
DISPLAY 1.595745 (-2775 4525);
PAINT GREEN (-2775 4525);
DISPLAY INVISIBLE (-2775 4525);
FORCEPROP 1 LAST HDL_TAP TRUE
J 2
(-3100 4450);
DISPLAY 1.595745 (-3100 4450);
PAINT GREEN (-3100 4450);
DISPLAY INVISIBLE (-3100 4450);
FORCEPROP 1 LAST PATH I169
J 2
(-2773 4575);
DISPLAY 0.872340 (-2773 4575);
PAINT GREEN (-2773 4575);
DISPLAY INVISIBLE (-2773 4575);
FORCEADD TAP..6
(-5500 1225);
FORCEPROP 3 LASTPIN (-5450 1225) SIG_NAME M_D_ECC<3>
J 0
(-5440 1235);
DISPLAY 0.659574 (-5440 1235);
PAINT MONO (-5440 1235);
DISPLAY INVISIBLE (-5440 1235);
FORCEPROP 1 LASTPIN (-5450 1225) BN 3
J 0
(-5502 1233);
DISPLAY 0.617021 (-5502 1233);
PAINT PINK (-5502 1233);
FORCEPROP 2 LAST CDS_LIB mstr_standard
J 0
(-5500 1225);
PAINT MONO (-5500 1225);
DISPLAY INVISIBLE (-5500 1225);
FORCEPROP 1 LAST BODY_TYPE PLUMBING
J 0
(-5500 1175);
DISPLAY 1.595745 (-5500 1175);
PAINT GREEN (-5500 1175);
DISPLAY INVISIBLE (-5500 1175);
FORCEPROP 1 LAST HDL_TAP TRUE
J 0
(-5175 1100);
DISPLAY 1.595745 (-5175 1100);
PAINT GREEN (-5175 1100);
DISPLAY INVISIBLE (-5175 1100);
FORCEPROP 1 LAST PATH I17
J 0
(-5502 1225);
DISPLAY 0.872340 (-5502 1225);
PAINT GREEN (-5502 1225);
DISPLAY INVISIBLE (-5502 1225);
FORCEADD TAP..6
R 2
(-2775 4675);
FORCEPROP 3 LASTPIN (-2825 4675) SIG_NAME M_D_DQS_DP<17>
J 0
(-2815 4685);
DISPLAY 0.659574 (-2815 4685);
PAINT MONO (-2815 4685);
DISPLAY INVISIBLE (-2815 4685);
FORCEPROP 1 LASTPIN (-2825 4675) BN 17
J 2
(-2773 4683);
DISPLAY 0.617021 (-2773 4683);
PAINT PINK (-2773 4683);
FORCEPROP 2 LAST CDS_LIB mstr_standard
J 2
(-2775 4675);
PAINT MONO (-2775 4675);
DISPLAY INVISIBLE (-2775 4675);
FORCEPROP 1 LAST BODY_TYPE PLUMBING
J 2
(-2775 4625);
DISPLAY 1.595745 (-2775 4625);
PAINT GREEN (-2775 4625);
DISPLAY INVISIBLE (-2775 4625);
FORCEPROP 1 LAST HDL_TAP TRUE
J 2
(-3100 4550);
DISPLAY 1.595745 (-3100 4550);
PAINT GREEN (-3100 4550);
DISPLAY INVISIBLE (-3100 4550);
FORCEPROP 1 LAST PATH I170
J 2
(-2773 4675);
DISPLAY 0.872340 (-2773 4675);
PAINT GREEN (-2773 4675);
DISPLAY INVISIBLE (-2773 4675);
FORCEADD OFFPAGE..3
(-1925 4750);
FORCEPROP 2 LAST $XR0 49 
J 0
(-1711 4750);
DISPLAY 0.638298 (-1711 4750);
PAINT MONO (-1711 4750);
FORCEPROP 2 LAST $XR1 50 
J 0
(-1621 4750);
DISPLAY 0.638298 (-1621 4750);
PAINT MONO (-1621 4750);
FORCEPROP 2 LAST CDS_LIB mstr_standard
J 0
(-1925 4750);
PAINT MONO (-1925 4750);
DISPLAY INVISIBLE (-1925 4750);
FORCEPROP 1 LAST OFFPAGE TRUE
J 0
(-1600 4625);
DISPLAY 1.170213 (-1600 4625);
PAINT GREEN (-1600 4625);
DISPLAY INVISIBLE (-1600 4625);
FORCEPROP 1 LAST COMMENT_BODY TRUE
J 0
(-1975 4650);
DISPLAY 1.170213 (-1975 4650);
PAINT GREEN (-1975 4650);
DISPLAY INVISIBLE (-1975 4650);
FORCEPROP 2 LAST PATH I171
J 0
(-1725 4825);
DISPLAY 1.021277 (-1725 4825);
PAINT ORANGE (-1725 4825);
DISPLAY INVISIBLE (-1725 4825);
FORCEADD SKX_EXT_B..6
(-4100 2575);
FORCEPROP 1 LAST LOCATION U5D1
J 0
(-4900 4925);
DISPLAY 0.617021 (-4900 4925);
PAINT AQUA (-4900 4925);
FORCEPROP 1 LAST PART_NUMBER TBD
J 0
(-4900 325);
DISPLAY 0.617021 (-4900 325);
PAINT BLUE (-4900 325);
FORCEPROP 1 LAST MATERIAL IC
J 0
(-4900 4875);
DISPLAY 0.617021 (-4900 4875);
PAINT SKYBLUE (-4900 4875);
FORCEPROP 2 LASTPIN (-3250 525) $PN ED53
J 0
(-3240 535);
DISPLAY 0.617021 (-3240 535);
PAINT ORANGE (-3240 535);
FORCEPROP 2 LASTPIN (-3250 1575) $PN EA48
J 0
(-3240 1585);
DISPLAY 0.617021 (-3240 1585);
PAINT ORANGE (-3240 1585);
FORCEPROP 2 LASTPIN (-3250 1525) $PN EA50
J 0
(-3240 1535);
DISPLAY 0.617021 (-3240 1535);
PAINT ORANGE (-3240 1535);
FORCEPROP 2 LASTPIN (-3250 1475) $PN EE48
J 0
(-3240 1485);
DISPLAY 0.617021 (-3240 1485);
PAINT ORANGE (-3240 1485);
FORCEPROP 2 LASTPIN (-3250 1425) $PN EE50
J 0
(-3240 1435);
DISPLAY 0.617021 (-3240 1435);
PAINT ORANGE (-3240 1435);
FORCEPROP 2 LASTPIN (-3250 2775) $PN EA46
J 0
(-3240 2785);
DISPLAY 0.617021 (-3240 2785);
PAINT ORANGE (-3240 2785);
FORCEPROP 2 LASTPIN (-3250 2725) $PN EA52
J 0
(-3240 2735);
DISPLAY 0.617021 (-3240 2735);
PAINT ORANGE (-3240 2735);
FORCEPROP 2 LASTPIN (-3250 2675) $PN DV49
J 0
(-3240 2685);
DISPLAY 0.617021 (-3240 2685);
PAINT ORANGE (-3240 2685);
FORCEPROP 2 LASTPIN (-3250 2625) $PN ED51
J 0
(-3240 2635);
DISPLAY 0.617021 (-3240 2635);
PAINT ORANGE (-3240 2635);
FORCEPROP 2 LASTPIN (-3250 2575) $PN DW48
J 0
(-3240 2585);
DISPLAY 0.617021 (-3240 2585);
PAINT ORANGE (-3240 2585);
FORCEPROP 2 LASTPIN (-3250 2525) $PN DT63
J 0
(-3240 2535);
DISPLAY 0.617021 (-3240 2535);
PAINT ORANGE (-3240 2535);
FORCEPROP 2 LASTPIN (-3250 2475) $PN EB61
J 0
(-3240 2485);
DISPLAY 0.617021 (-3240 2485);
PAINT ORANGE (-3240 2485);
FORCEPROP 2 LASTPIN (-3250 2425) $PN DW54
J 0
(-3240 2435);
DISPLAY 0.617021 (-3240 2435);
PAINT ORANGE (-3240 2435);
FORCEPROP 2 LASTPIN (-3250 2375) $PN EF61
J 0
(-3240 2385);
DISPLAY 0.617021 (-3240 2385);
PAINT ORANGE (-3240 2385);
FORCEPROP 2 LASTPIN (-3250 2325) $PN EB59
J 0
(-3240 2335);
DISPLAY 0.617021 (-3240 2335);
PAINT ORANGE (-3240 2335);
FORCEPROP 2 LASTPIN (-3250 2275) $PN EA60
J 0
(-3240 2285);
DISPLAY 0.617021 (-3240 2285);
PAINT ORANGE (-3240 2285);
FORCEPROP 2 LASTPIN (-3250 2225) $PN EE60
J 0
(-3240 2235);
DISPLAY 0.617021 (-3240 2235);
PAINT ORANGE (-3240 2235);
FORCEPROP 2 LASTPIN (-3250 2175) $PN EA58
J 0
(-3240 2185);
DISPLAY 0.617021 (-3240 2185);
PAINT ORANGE (-3240 2185);
FORCEPROP 2 LASTPIN (-3250 2125) $PN ED59
J 0
(-3240 2135);
DISPLAY 0.617021 (-3240 2135);
PAINT ORANGE (-3240 2135);
FORCEPROP 2 LASTPIN (-3250 2075) $PN EB57
J 0
(-3240 2085);
DISPLAY 0.617021 (-3240 2085);
PAINT ORANGE (-3240 2085);
FORCEPROP 2 LASTPIN (-3250 2025) $PN EE58
J 0
(-3240 2035);
DISPLAY 0.617021 (-3240 2035);
PAINT ORANGE (-3240 2035);
FORCEPROP 2 LASTPIN (-3250 1975) $PN ED57
J 0
(-3240 1985);
DISPLAY 0.617021 (-3240 1985);
PAINT ORANGE (-3240 1985);
FORCEPROP 2 LASTPIN (-3250 1925) $PN EB53
J 0
(-3240 1935);
DISPLAY 0.617021 (-3240 1935);
PAINT ORANGE (-3240 1935);
FORCEPROP 2 LASTPIN (-4950 1425) $PN DE66
J 2
(-4960 1435);
DISPLAY 0.617021 (-4960 1435);
PAINT ORANGE (-4960 1435);
FORCEPROP 2 LASTPIN (-4950 1375) $PN DA66
J 2
(-4960 1385);
DISPLAY 0.617021 (-4960 1385);
PAINT ORANGE (-4960 1385);
FORCEPROP 2 LASTPIN (-4950 1325) $PN DD69
J 2
(-4960 1335);
DISPLAY 0.617021 (-4960 1335);
PAINT ORANGE (-4960 1335);
FORCEPROP 2 LASTPIN (-4950 1275) $PN DB69
J 2
(-4960 1285);
DISPLAY 0.617021 (-4960 1285);
PAINT ORANGE (-4960 1285);
FORCEPROP 2 LASTPIN (-4950 1225) $PN DD65
J 2
(-4960 1235);
DISPLAY 0.617021 (-4960 1235);
PAINT ORANGE (-4960 1235);
FORCEPROP 2 LASTPIN (-4950 1175) $PN DB65
J 2
(-4960 1185);
DISPLAY 0.617021 (-4960 1185);
PAINT ORANGE (-4960 1185);
FORCEPROP 2 LASTPIN (-4950 1125) $PN DE68
J 2
(-4960 1135);
DISPLAY 0.617021 (-4960 1135);
PAINT ORANGE (-4960 1135);
FORCEPROP 2 LASTPIN (-4950 1075) $PN DA68
J 2
(-4960 1085);
DISPLAY 0.617021 (-4960 1085);
PAINT ORANGE (-4960 1085);
FORCEPROP 2 LASTPIN (-3250 4675) $PN CY67
J 0
(-3240 4685);
DISPLAY 0.617021 (-3240 4685);
PAINT ORANGE (-3240 4685);
FORCEPROP 2 LASTPIN (-3250 4625) $PN DP23
J 0
(-3240 4635);
DISPLAY 0.617021 (-3240 4635);
PAINT ORANGE (-3240 4635);
FORCEPROP 2 LASTPIN (-3250 4575) $PN DP29
J 0
(-3240 4585);
DISPLAY 0.617021 (-3240 4585);
PAINT ORANGE (-3240 4585);
FORCEPROP 2 LASTPIN (-3250 4525) $PN DM35
J 0
(-3240 4535);
DISPLAY 0.617021 (-3240 4535);
PAINT ORANGE (-3240 4535);
FORCEPROP 2 LASTPIN (-3250 4475) $PN DW38
J 0
(-3240 4485);
DISPLAY 0.617021 (-3240 4485);
PAINT ORANGE (-3240 4485);
FORCEPROP 2 LASTPIN (-3250 4425) $PN DM75
J 0
(-3240 4435);
DISPLAY 0.617021 (-3240 4435);
PAINT ORANGE (-3240 4435);
FORCEPROP 2 LASTPIN (-3250 4375) $PN DP79
J 0
(-3240 4385);
DISPLAY 0.617021 (-3240 4385);
PAINT ORANGE (-3240 4385);
FORCEPROP 2 LASTPIN (-3250 4325) $PN DL84
J 0
(-3240 4335);
DISPLAY 0.617021 (-3240 4335);
PAINT ORANGE (-3240 4335);
FORCEPROP 2 LASTPIN (-3250 4275) $PN CP85
J 0
(-3240 4285);
DISPLAY 0.617021 (-3240 4285);
PAINT ORANGE (-3240 4285);
FORCEPROP 2 LASTPIN (-3250 4225) $PN DD67
J 0
(-3240 4235);
DISPLAY 0.617021 (-3240 4235);
PAINT ORANGE (-3240 4235);
FORCEPROP 2 LASTPIN (-3250 4175) $PN DT23
J 0
(-3240 4185);
DISPLAY 0.617021 (-3240 4185);
PAINT ORANGE (-3240 4185);
FORCEPROP 2 LASTPIN (-3250 4125) $PN DT29
J 0
(-3240 4135);
DISPLAY 0.617021 (-3240 4135);
PAINT ORANGE (-3240 4135);
FORCEPROP 2 LASTPIN (-3250 4075) $PN DT35
J 0
(-3240 4085);
DISPLAY 0.617021 (-3240 4085);
PAINT ORANGE (-3240 4085);
FORCEPROP 2 LASTPIN (-3250 4025) $PN EC38
J 0
(-3240 4035);
DISPLAY 0.617021 (-3240 4035);
PAINT ORANGE (-3240 4035);
FORCEPROP 2 LASTPIN (-3250 3975) $PN DT75
J 0
(-3240 3985);
DISPLAY 0.617021 (-3240 3985);
PAINT ORANGE (-3240 3985);
FORCEPROP 2 LASTPIN (-3250 3925) $PN DM81
J 0
(-3240 3935);
DISPLAY 0.617021 (-3240 3935);
PAINT ORANGE (-3240 3935);
FORCEPROP 2 LASTPIN (-3250 3875) $PN DP85
J 0
(-3240 3885);
DISPLAY 0.617021 (-3240 3885);
PAINT ORANGE (-3240 3885);
FORCEPROP 2 LASTPIN (-3250 3825) $PN CV85
J 0
(-3240 3835);
DISPLAY 0.617021 (-3240 3835);
PAINT ORANGE (-3240 3835);
FORCEPROP 2 LASTPIN (-3250 3725) $PN DB67
J 0
(-3240 3735);
DISPLAY 0.617021 (-3240 3735);
PAINT ORANGE (-3240 3735);
FORCEPROP 2 LASTPIN (-3250 3675) $PN DM23
J 0
(-3240 3685);
DISPLAY 0.617021 (-3240 3685);
PAINT ORANGE (-3240 3685);
FORCEPROP 2 LASTPIN (-3250 3625) $PN DM29
J 0
(-3240 3635);
DISPLAY 0.617021 (-3240 3635);
PAINT ORANGE (-3240 3635);
FORCEPROP 2 LASTPIN (-3250 3575) $PN DP35
J 0
(-3240 3585);
DISPLAY 0.617021 (-3240 3585);
PAINT ORANGE (-3240 3585);
FORCEPROP 2 LASTPIN (-3250 3525) $PN EA38
J 0
(-3240 3535);
DISPLAY 0.617021 (-3240 3535);
PAINT ORANGE (-3240 3535);
FORCEPROP 2 LASTPIN (-3250 3475) $PN DP75
J 0
(-3240 3485);
DISPLAY 0.617021 (-3240 3485);
PAINT ORANGE (-3240 3485);
FORCEPROP 2 LASTPIN (-3250 3425) $PN DN80
J 0
(-3240 3435);
DISPLAY 0.617021 (-3240 3435);
PAINT ORANGE (-3240 3435);
FORCEPROP 2 LASTPIN (-3250 3375) $PN DM85
J 0
(-3240 3385);
DISPLAY 0.617021 (-3240 3385);
PAINT ORANGE (-3240 3385);
FORCEPROP 2 LASTPIN (-3250 3325) $PN CR84
J 0
(-3240 3335);
DISPLAY 0.617021 (-3240 3335);
PAINT ORANGE (-3240 3335);
FORCEPROP 2 LASTPIN (-3250 3275) $PN DF67
J 0
(-3240 3285);
DISPLAY 0.617021 (-3240 3285);
PAINT ORANGE (-3240 3285);
FORCEPROP 2 LASTPIN (-3250 3225) $PN DV23
J 0
(-3240 3235);
DISPLAY 0.617021 (-3240 3235);
PAINT ORANGE (-3240 3235);
FORCEPROP 2 LASTPIN (-3250 3175) $PN DV29
J 0
(-3240 3185);
DISPLAY 0.617021 (-3240 3185);
PAINT ORANGE (-3240 3185);
FORCEPROP 2 LASTPIN (-3250 3125) $PN DV35
J 0
(-3240 3135);
DISPLAY 0.617021 (-3240 3135);
PAINT ORANGE (-3240 3135);
FORCEPROP 2 LASTPIN (-3250 3075) $PN EE38
J 0
(-3240 3085);
DISPLAY 0.617021 (-3240 3085);
PAINT ORANGE (-3240 3085);
FORCEPROP 2 LASTPIN (-3250 3025) $PN DV75
J 0
(-3240 3035);
DISPLAY 0.617021 (-3240 3035);
PAINT ORANGE (-3240 3035);
FORCEPROP 2 LASTPIN (-3250 2975) $PN DL82
J 0
(-3240 2985);
DISPLAY 0.617021 (-3240 2985);
PAINT ORANGE (-3240 2985);
FORCEPROP 2 LASTPIN (-3250 2925) $PN DN84
J 0
(-3240 2935);
DISPLAY 0.617021 (-3240 2935);
PAINT ORANGE (-3240 2935);
FORCEPROP 2 LASTPIN (-3250 2875) $PN CU84
J 0
(-3240 2885);
DISPLAY 0.617021 (-3240 2885);
PAINT ORANGE (-3240 2885);
FORCEPROP 2 LASTPIN (-4950 4675) $PN DW22
J 2
(-4960 4685);
DISPLAY 0.617021 (-4960 4685);
PAINT ORANGE (-4960 4685);
FORCEPROP 2 LASTPIN (-4950 4625) $PN EC22
J 2
(-4960 4635);
DISPLAY 0.617021 (-4960 4635);
PAINT ORANGE (-4960 4635);
FORCEPROP 2 LASTPIN (-4950 4575) $PN DT25
J 2
(-4960 4585);
DISPLAY 0.617021 (-4960 4585);
PAINT ORANGE (-4960 4585);
FORCEPROP 2 LASTPIN (-4950 4525) $PN DP25
J 2
(-4960 4535);
DISPLAY 0.617021 (-4960 4535);
PAINT ORANGE (-4960 4535);
FORCEPROP 2 LASTPIN (-4950 4475) $PN EB21
J 2
(-4960 4485);
DISPLAY 0.617021 (-4960 4485);
PAINT ORANGE (-4960 4485);
FORCEPROP 2 LASTPIN (-4950 4425) $PN DY21
J 2
(-4960 4435);
DISPLAY 0.617021 (-4960 4435);
PAINT ORANGE (-4960 4435);
FORCEPROP 2 LASTPIN (-4950 4375) $PN DU24
J 2
(-4960 4385);
DISPLAY 0.617021 (-4960 4385);
PAINT ORANGE (-4960 4385);
FORCEPROP 2 LASTPIN (-4950 4325) $PN DN24
J 2
(-4960 4335);
DISPLAY 0.617021 (-4960 4335);
PAINT ORANGE (-4960 4335);
FORCEPROP 2 LASTPIN (-4950 4275) $PN DU28
J 2
(-4960 4285);
DISPLAY 0.617021 (-4960 4285);
PAINT ORANGE (-4960 4285);
FORCEPROP 2 LASTPIN (-4950 4225) $PN DN28
J 2
(-4960 4235);
DISPLAY 0.617021 (-4960 4235);
PAINT ORANGE (-4960 4235);
FORCEPROP 2 LASTPIN (-4950 4175) $PN DT31
J 2
(-4960 4185);
DISPLAY 0.617021 (-4960 4185);
PAINT ORANGE (-4960 4185);
FORCEPROP 2 LASTPIN (-4950 4125) $PN DP31
J 2
(-4960 4135);
DISPLAY 0.617021 (-4960 4135);
PAINT ORANGE (-4960 4135);
FORCEPROP 2 LASTPIN (-4950 4075) $PN DT27
J 2
(-4960 4085);
DISPLAY 0.617021 (-4960 4085);
PAINT ORANGE (-4960 4085);
FORCEPROP 2 LASTPIN (-4950 4025) $PN DP27
J 2
(-4960 4035);
DISPLAY 0.617021 (-4960 4035);
PAINT ORANGE (-4960 4035);
FORCEPROP 2 LASTPIN (-4950 3975) $PN DU30
J 2
(-4960 3985);
DISPLAY 0.617021 (-4960 3985);
PAINT ORANGE (-4960 3985);
FORCEPROP 2 LASTPIN (-4950 3925) $PN DN30
J 2
(-4960 3935);
DISPLAY 0.617021 (-4960 3935);
PAINT ORANGE (-4960 3935);
FORCEPROP 2 LASTPIN (-4950 3875) $PN DU34
J 2
(-4960 3885);
DISPLAY 0.617021 (-4960 3885);
PAINT ORANGE (-4960 3885);
FORCEPROP 2 LASTPIN (-4950 3825) $PN DN34
J 2
(-4960 3835);
DISPLAY 0.617021 (-4960 3835);
PAINT ORANGE (-4960 3835);
FORCEPROP 2 LASTPIN (-4950 3775) $PN DT37
J 2
(-4960 3785);
DISPLAY 0.617021 (-4960 3785);
PAINT ORANGE (-4960 3785);
FORCEPROP 2 LASTPIN (-4950 3725) $PN DP37
J 2
(-4960 3735);
DISPLAY 0.617021 (-4960 3735);
PAINT ORANGE (-4960 3735);
FORCEPROP 2 LASTPIN (-4950 3675) $PN DT33
J 2
(-4960 3685);
DISPLAY 0.617021 (-4960 3685);
PAINT ORANGE (-4960 3685);
FORCEPROP 2 LASTPIN (-4950 3625) $PN DP33
J 2
(-4960 3635);
DISPLAY 0.617021 (-4960 3635);
PAINT ORANGE (-4960 3635);
FORCEPROP 2 LASTPIN (-4950 3575) $PN DU36
J 2
(-4960 3585);
DISPLAY 0.617021 (-4960 3585);
PAINT ORANGE (-4960 3585);
FORCEPROP 2 LASTPIN (-4950 3525) $PN DN36
J 2
(-4960 3535);
DISPLAY 0.617021 (-4960 3535);
PAINT ORANGE (-4960 3535);
FORCEPROP 2 LASTPIN (-4950 3475) $PN ED37
J 2
(-4960 3485);
DISPLAY 0.617021 (-4960 3485);
PAINT ORANGE (-4960 3485);
FORCEPROP 2 LASTPIN (-4950 3425) $PN DY37
J 2
(-4960 3435);
DISPLAY 0.617021 (-4960 3435);
PAINT ORANGE (-4960 3435);
FORCEPROP 2 LASTPIN (-4950 3375) $PN EA40
J 2
(-4960 3385);
DISPLAY 0.617021 (-4960 3385);
PAINT ORANGE (-4960 3385);
FORCEPROP 2 LASTPIN (-4950 3325) $PN DY39
J 2
(-4960 3335);
DISPLAY 0.617021 (-4960 3335);
PAINT ORANGE (-4960 3335);
FORCEPROP 2 LASTPIN (-4950 3275) $PN EC36
J 2
(-4960 3285);
DISPLAY 0.617021 (-4960 3285);
PAINT ORANGE (-4960 3285);
FORCEPROP 2 LASTPIN (-4950 3225) $PN EA36
J 2
(-4960 3235);
DISPLAY 0.617021 (-4960 3235);
PAINT ORANGE (-4960 3235);
FORCEPROP 2 LASTPIN (-4950 3175) $PN ED39
J 2
(-4960 3185);
DISPLAY 0.617021 (-4960 3185);
PAINT ORANGE (-4960 3185);
FORCEPROP 2 LASTPIN (-4950 3125) $PN EC40
J 2
(-4960 3135);
DISPLAY 0.617021 (-4960 3135);
PAINT ORANGE (-4960 3135);
FORCEPROP 2 LASTPIN (-4950 3075) $PN DU74
J 2
(-4960 3085);
DISPLAY 0.617021 (-4960 3085);
PAINT ORANGE (-4960 3085);
FORCEPROP 2 LASTPIN (-4950 3025) $PN DN74
J 2
(-4960 3035);
DISPLAY 0.617021 (-4960 3035);
PAINT ORANGE (-4960 3035);
FORCEPROP 2 LASTPIN (-4950 2975) $PN DT77
J 2
(-4960 2985);
DISPLAY 0.617021 (-4960 2985);
PAINT ORANGE (-4960 2985);
FORCEPROP 2 LASTPIN (-4950 2925) $PN DP77
J 2
(-4960 2935);
DISPLAY 0.617021 (-4960 2935);
PAINT ORANGE (-4960 2935);
FORCEPROP 2 LASTPIN (-4950 2875) $PN DT73
J 2
(-4960 2885);
DISPLAY 0.617021 (-4960 2885);
PAINT ORANGE (-4960 2885);
FORCEPROP 2 LASTPIN (-4950 2825) $PN DP73
J 2
(-4960 2835);
DISPLAY 0.617021 (-4960 2835);
PAINT ORANGE (-4960 2835);
FORCEPROP 2 LASTPIN (-4950 2775) $PN DU76
J 2
(-4960 2785);
DISPLAY 0.617021 (-4960 2785);
PAINT ORANGE (-4960 2785);
FORCEPROP 2 LASTPIN (-4950 2725) $PN DN76
J 2
(-4960 2735);
DISPLAY 0.617021 (-4960 2735);
PAINT ORANGE (-4960 2735);
FORCEPROP 2 LASTPIN (-4950 2675) $PN DN82
J 2
(-4960 2685);
DISPLAY 0.617021 (-4960 2685);
PAINT ORANGE (-4960 2685);
FORCEPROP 2 LASTPIN (-4950 2625) $PN DR80
J 2
(-4960 2635);
DISPLAY 0.617021 (-4960 2635);
PAINT ORANGE (-4960 2635);
FORCEPROP 2 LASTPIN (-4950 2575) $PN DJ80
J 2
(-4960 2585);
DISPLAY 0.617021 (-4960 2585);
PAINT ORANGE (-4960 2585);
FORCEPROP 2 LASTPIN (-4950 2525) $PN DK79
J 2
(-4960 2535);
DISPLAY 0.617021 (-4960 2535);
PAINT ORANGE (-4960 2535);
FORCEPROP 2 LASTPIN (-4950 2475) $PN DR82
J 2
(-4960 2485);
DISPLAY 0.617021 (-4960 2485);
PAINT ORANGE (-4960 2485);
FORCEPROP 2 LASTPIN (-4950 2425) $PN DT81
J 2
(-4960 2435);
DISPLAY 0.617021 (-4960 2435);
PAINT ORANGE (-4960 2435);
FORCEPROP 2 LASTPIN (-4950 2375) $PN DK81
J 2
(-4960 2385);
DISPLAY 0.617021 (-4960 2385);
PAINT ORANGE (-4960 2385);
FORCEPROP 2 LASTPIN (-4950 2325) $PN DM79
J 2
(-4960 2335);
DISPLAY 0.617021 (-4960 2335);
PAINT ORANGE (-4960 2335);
FORCEPROP 2 LASTPIN (-4950 2275) $PN DV85
J 2
(-4960 2285);
DISPLAY 0.617021 (-4960 2285);
PAINT ORANGE (-4960 2285);
FORCEPROP 2 LASTPIN (-4950 2225) $PN DR84
J 2
(-4960 2235);
DISPLAY 0.617021 (-4960 2235);
PAINT ORANGE (-4960 2235);
FORCEPROP 2 LASTPIN (-4950 2175) $PN DE84
J 2
(-4960 2185);
DISPLAY 0.617021 (-4960 2185);
PAINT ORANGE (-4960 2185);
FORCEPROP 2 LASTPIN (-4950 2125) $PN DD85
J 2
(-4960 2135);
DISPLAY 0.617021 (-4960 2135);
PAINT ORANGE (-4960 2135);
FORCEPROP 2 LASTPIN (-4950 2075) $PN DY83
J 2
(-4960 2085);
DISPLAY 0.617021 (-4960 2085);
PAINT ORANGE (-4960 2085);
FORCEPROP 2 LASTPIN (-4950 2025) $PN DV83
J 2
(-4960 2035);
DISPLAY 0.617021 (-4960 2035);
PAINT ORANGE (-4960 2035);
FORCEPROP 2 LASTPIN (-4950 1975) $PN DH85
J 2
(-4960 1985);
DISPLAY 0.617021 (-4960 1985);
PAINT ORANGE (-4960 1985);
FORCEPROP 2 LASTPIN (-4950 1925) $PN DG84
J 2
(-4960 1935);
DISPLAY 0.617021 (-4960 1935);
PAINT ORANGE (-4960 1935);
FORCEPROP 2 LASTPIN (-4950 1875) $PN CW84
J 2
(-4960 1885);
DISPLAY 0.617021 (-4960 1885);
PAINT ORANGE (-4960 1885);
FORCEPROP 2 LASTPIN (-4950 1825) $PN CW86
J 2
(-4960 1835);
DISPLAY 0.617021 (-4960 1835);
PAINT ORANGE (-4960 1835);
FORCEPROP 2 LASTPIN (-4950 1775) $PN CL86
J 2
(-4960 1785);
DISPLAY 0.617021 (-4960 1785);
PAINT ORANGE (-4960 1785);
FORCEPROP 2 LASTPIN (-4950 1725) $PN CL84
J 2
(-4960 1735);
DISPLAY 0.617021 (-4960 1735);
PAINT ORANGE (-4960 1735);
FORCEPROP 2 LASTPIN (-4950 1675) $PN DA84
J 2
(-4960 1685);
DISPLAY 0.617021 (-4960 1685);
PAINT ORANGE (-4960 1685);
FORCEPROP 2 LASTPIN (-4950 1625) $PN DA86
J 2
(-4960 1635);
DISPLAY 0.617021 (-4960 1635);
PAINT ORANGE (-4960 1635);
FORCEPROP 2 LASTPIN (-4950 1575) $PN CN86
J 2
(-4960 1585);
DISPLAY 0.617021 (-4960 1585);
PAINT ORANGE (-4960 1585);
FORCEPROP 2 LASTPIN (-4950 1525) $PN CN84
J 2
(-4960 1535);
DISPLAY 0.617021 (-4960 1535);
PAINT ORANGE (-4960 1535);
FORCEPROP 2 LASTPIN (-3250 1325) $PN EB45
J 0
(-3240 1335);
DISPLAY 0.617021 (-3240 1335);
PAINT ORANGE (-3240 1335);
FORCEPROP 2 LASTPIN (-3250 1275) $PN DV45
J 0
(-3240 1285);
DISPLAY 0.617021 (-3240 1285);
PAINT ORANGE (-3240 1285);
FORCEPROP 2 LASTPIN (-3250 1225) $PN EB49
J 0
(-3240 1235);
DISPLAY 0.617021 (-3240 1235);
PAINT ORANGE (-3240 1235);
FORCEPROP 2 LASTPIN (-3250 1175) $PN EB51
J 0
(-3240 1185);
DISPLAY 0.617021 (-3240 1185);
PAINT ORANGE (-3240 1185);
FORCEPROP 2 LASTPIN (-3250 1125) $PN EB47
J 0
(-3240 1135);
DISPLAY 0.617021 (-3240 1135);
PAINT ORANGE (-3240 1135);
FORCEPROP 2 LASTPIN (-3250 1075) $PN ED47
J 0
(-3240 1085);
DISPLAY 0.617021 (-3240 1085);
PAINT ORANGE (-3240 1085);
FORCEPROP 2 LASTPIN (-3250 1025) $PN ED49
J 0
(-3240 1035);
DISPLAY 0.617021 (-3240 1035);
PAINT ORANGE (-3240 1035);
FORCEPROP 2 LASTPIN (-3250 975) $PN EF51
J 0
(-3240 985);
DISPLAY 0.617021 (-3240 985);
PAINT ORANGE (-3240 985);
FORCEPROP 2 LASTPIN (-4950 975) $PN EE56
J 2
(-4960 985);
DISPLAY 0.617021 (-4960 985);
PAINT ORANGE (-4960 985);
FORCEPROP 2 LASTPIN (-4950 925) $PN EA56
J 2
(-4960 935);
DISPLAY 0.617021 (-4960 935);
PAINT ORANGE (-4960 935);
FORCEPROP 2 LASTPIN (-4950 875) $PN EE54
J 2
(-4960 885);
DISPLAY 0.617021 (-4960 885);
PAINT ORANGE (-4960 885);
FORCEPROP 2 LASTPIN (-4950 825) $PN EB55
J 2
(-4960 835);
DISPLAY 0.617021 (-4960 835);
PAINT ORANGE (-4960 835);
FORCEPROP 2 LASTPIN (-4950 775) $PN EF57
J 2
(-4960 785);
DISPLAY 0.617021 (-4960 785);
PAINT ORANGE (-4960 785);
FORCEPROP 2 LASTPIN (-4950 725) $PN DW56
J 2
(-4960 735);
DISPLAY 0.617021 (-4960 735);
PAINT ORANGE (-4960 735);
FORCEPROP 2 LASTPIN (-4950 675) $PN EF55
J 2
(-4960 685);
DISPLAY 0.617021 (-4960 685);
PAINT ORANGE (-4960 685);
FORCEPROP 2 LASTPIN (-4950 625) $PN ED55
J 2
(-4960 635);
DISPLAY 0.617021 (-4960 635);
PAINT ORANGE (-4960 635);
FORCEPROP 2 LASTPIN (-3250 1825) $PN EB63
J 0
(-3240 1835);
DISPLAY 0.617021 (-3240 1835);
PAINT ORANGE (-3240 1835);
FORCEPROP 2 LASTPIN (-3250 1775) $PN EA62
J 0
(-3240 1785);
DISPLAY 0.617021 (-3240 1785);
PAINT ORANGE (-3240 1785);
FORCEPROP 2 LASTPIN (-3250 1725) $PN EF63
J 0
(-3240 1735);
DISPLAY 0.617021 (-3240 1735);
PAINT ORANGE (-3240 1735);
FORCEPROP 2 LASTPIN (-3250 1675) $PN EE62
J 0
(-3240 1685);
DISPLAY 0.617021 (-3240 1685);
PAINT ORANGE (-3240 1685);
FORCEPROP 2 LASTPIN (-4950 525) $PN DV47
J 2
(-4960 535);
DISPLAY 0.617021 (-4960 535);
PAINT ORANGE (-4960 535);
FORCEPROP 2 LASTPIN (-3250 875) $PN DW62
J 0
(-3240 885);
DISPLAY 0.617021 (-3240 885);
PAINT ORANGE (-3240 885);
FORCEPROP 2 LASTPIN (-3250 825) $PN ED61
J 0
(-3240 835);
DISPLAY 0.617021 (-3240 835);
PAINT ORANGE (-3240 835);
FORCEPROP 2 LASTPIN (-3250 775) $PN EA54
J 0
(-3240 785);
DISPLAY 0.617021 (-3240 785);
PAINT ORANGE (-3240 785);
FORCEPROP 2 LASTPIN (-3250 725) $PN EE52
J 0
(-3240 735);
DISPLAY 0.617021 (-3240 735);
PAINT ORANGE (-3240 735);
FORCEPROP 2 LASTPIN (-3250 575) $PN ED63
J 0
(-3240 585);
DISPLAY 0.617021 (-3240 585);
PAINT ORANGE (-3240 585);
FORCEPROP 2 LASTPIN (-3250 625) $PN DW60
J 0
(-3240 635);
DISPLAY 0.617021 (-3240 635);
PAINT ORANGE (-3240 635);
FORCEPROP 1 LAST PACK_TYPE BGA1
J 0
(-4900 4975);
PAINT SKYBLUE (-4900 4975);
DISPLAY INVISIBLE (-4900 4975);
FORCEPROP 2 LAST CDS_LIB chpset_lib
J 0
(-4100 2575);
PAINT ORANGE (-4100 2575);
DISPLAY INVISIBLE (-4100 2575);
FORCEPROP 2 LAST SEC_TYPE BGA1
J 0
(-4900 4975);
DISPLAY 1.021277 (-4900 4975);
PAINT ORANGE (-4900 4975);
DISPLAY INVISIBLE (-4900 4975);
FORCEPROP 2 LAST SEC 6
J 0
(-4900 4975);
DISPLAY 0.680851 (-4900 4975);
PAINT MONO (-4900 4975);
DISPLAY INVISIBLE (-4900 4975);
FORCEPROP 2 LAST CDS_LOCATION U5D1
J 0
(-4900 4925);
DISPLAY 0.617021 (-4900 4925);
PAINT AQUA (-4900 4925);
DISPLAY INVISIBLE (-4900 4925);
FORCEPROP 1 LAST PATH I172
J 0
(-4100 4875);
PAINT GREEN (-4100 4875);
DISPLAY INVISIBLE (-4100 4875);
FORCEPROP 0 LAST ROOM CPU0
J 0
(-4900 5025);
DISPLAY 1.021277 (-4900 5025);
PAINT ORANGE (-4900 5025);
DISPLAY INVISIBLE (-4900 5025);
FORCEADD TAP..6
(-5500 1325);
FORCEPROP 3 LASTPIN (-5450 1325) SIG_NAME M_D_ECC<5>
J 0
(-5440 1335);
DISPLAY 0.659574 (-5440 1335);
PAINT MONO (-5440 1335);
DISPLAY INVISIBLE (-5440 1335);
FORCEPROP 1 LASTPIN (-5450 1325) BN 5
J 0
(-5502 1333);
DISPLAY 0.617021 (-5502 1333);
PAINT PINK (-5502 1333);
FORCEPROP 2 LAST CDS_LIB mstr_standard
J 0
(-5500 1325);
PAINT MONO (-5500 1325);
DISPLAY INVISIBLE (-5500 1325);
FORCEPROP 1 LAST BODY_TYPE PLUMBING
J 0
(-5500 1275);
DISPLAY 1.595745 (-5500 1275);
PAINT GREEN (-5500 1275);
DISPLAY INVISIBLE (-5500 1275);
FORCEPROP 1 LAST HDL_TAP TRUE
J 0
(-5175 1200);
DISPLAY 1.595745 (-5175 1200);
PAINT GREEN (-5175 1200);
DISPLAY INVISIBLE (-5175 1200);
FORCEPROP 1 LAST PATH I18
J 0
(-5502 1325);
DISPLAY 0.872340 (-5502 1325);
PAINT GREEN (-5502 1325);
DISPLAY INVISIBLE (-5502 1325);
FORCEADD TAP..6
(-5500 1375);
FORCEPROP 3 LASTPIN (-5450 1375) SIG_NAME M_D_ECC<6>
J 0
(-5440 1385);
DISPLAY 0.659574 (-5440 1385);
PAINT MONO (-5440 1385);
DISPLAY INVISIBLE (-5440 1385);
FORCEPROP 1 LASTPIN (-5450 1375) BN 6
J 0
(-5502 1383);
DISPLAY 0.617021 (-5502 1383);
PAINT PINK (-5502 1383);
FORCEPROP 2 LAST CDS_LIB mstr_standard
J 0
(-5500 1375);
PAINT MONO (-5500 1375);
DISPLAY INVISIBLE (-5500 1375);
FORCEPROP 1 LAST BODY_TYPE PLUMBING
J 0
(-5500 1325);
DISPLAY 1.595745 (-5500 1325);
PAINT GREEN (-5500 1325);
DISPLAY INVISIBLE (-5500 1325);
FORCEPROP 1 LAST HDL_TAP TRUE
J 0
(-5175 1250);
DISPLAY 1.595745 (-5175 1250);
PAINT GREEN (-5175 1250);
DISPLAY INVISIBLE (-5175 1250);
FORCEPROP 1 LAST PATH I19
J 0
(-5502 1375);
DISPLAY 0.872340 (-5502 1375);
PAINT GREEN (-5502 1375);
DISPLAY INVISIBLE (-5502 1375);
FORCEADD OFFPAGE..5
(-6350 825);
FORCEPROP 2 LAST $XR0 49 
J 0
(-6574 825);
DISPLAY 0.638298 (-6574 825);
PAINT MONO (-6574 825);
FORCEPROP 2 LAST $XR1 50 
J 0
(-6664 825);
DISPLAY 0.638298 (-6664 825);
PAINT MONO (-6664 825);
FORCEPROP 2 LAST CDS_LIB mstr_standard
J 0
(-6350 825);
PAINT MONO (-6350 825);
DISPLAY INVISIBLE (-6350 825);
FORCEPROP 1 LAST OFFPAGE TRUE
J 0
(-6025 700);
DISPLAY 1.170213 (-6025 700);
PAINT GREEN (-6025 700);
DISPLAY INVISIBLE (-6025 700);
FORCEPROP 1 LAST COMMENT_BODY TRUE
J 0
(-6250 750);
DISPLAY 1.170213 (-6250 750);
PAINT GREEN (-6250 750);
DISPLAY INVISIBLE (-6250 750);
FORCEPROP 2 LAST PATH I2
J 0
(-6300 900);
DISPLAY 1.021277 (-6300 900);
PAINT ORANGE (-6300 900);
DISPLAY INVISIBLE (-6300 900);
FORCEADD TAP..6
(-5500 1425);
FORCEPROP 3 LASTPIN (-5450 1425) SIG_NAME M_D_ECC<7>
J 0
(-5440 1435);
DISPLAY 0.659574 (-5440 1435);
PAINT MONO (-5440 1435);
DISPLAY INVISIBLE (-5440 1435);
FORCEPROP 1 LASTPIN (-5450 1425) BN 7
J 0
(-5502 1433);
DISPLAY 0.617021 (-5502 1433);
PAINT PINK (-5502 1433);
FORCEPROP 2 LAST CDS_LIB mstr_standard
J 0
(-5500 1425);
PAINT MONO (-5500 1425);
DISPLAY INVISIBLE (-5500 1425);
FORCEPROP 1 LAST BODY_TYPE PLUMBING
J 0
(-5500 1375);
DISPLAY 1.595745 (-5500 1375);
PAINT GREEN (-5500 1375);
DISPLAY INVISIBLE (-5500 1375);
FORCEPROP 1 LAST HDL_TAP TRUE
J 0
(-5175 1300);
DISPLAY 1.595745 (-5175 1300);
PAINT GREEN (-5175 1300);
DISPLAY INVISIBLE (-5175 1300);
FORCEPROP 1 LAST PATH I20
J 0
(-5502 1425);
DISPLAY 0.872340 (-5502 1425);
PAINT GREEN (-5502 1425);
DISPLAY INVISIBLE (-5502 1425);
FORCEADD TAP..6
(-5500 1525);
FORCEPROP 3 LASTPIN (-5450 1525) SIG_NAME M_D_DQ<0>
J 0
(-5440 1535);
DISPLAY 0.659574 (-5440 1535);
PAINT MONO (-5440 1535);
DISPLAY INVISIBLE (-5440 1535);
FORCEPROP 1 LASTPIN (-5450 1525) BN 0
J 0
(-5502 1533);
DISPLAY 0.617021 (-5502 1533);
PAINT PINK (-5502 1533);
FORCEPROP 2 LAST CDS_LIB mstr_standard
J 0
(-5500 1525);
PAINT MONO (-5500 1525);
DISPLAY INVISIBLE (-5500 1525);
FORCEPROP 1 LAST BODY_TYPE PLUMBING
J 0
(-5500 1475);
DISPLAY 1.595745 (-5500 1475);
PAINT GREEN (-5500 1475);
DISPLAY INVISIBLE (-5500 1475);
FORCEPROP 1 LAST HDL_TAP TRUE
J 0
(-5175 1400);
DISPLAY 1.595745 (-5175 1400);
PAINT GREEN (-5175 1400);
DISPLAY INVISIBLE (-5175 1400);
FORCEPROP 1 LAST PATH I21
J 0
(-5502 1525);
DISPLAY 0.872340 (-5502 1525);
PAINT GREEN (-5502 1525);
DISPLAY INVISIBLE (-5502 1525);
FORCEADD TAP..6
(-5500 1575);
FORCEPROP 3 LASTPIN (-5450 1575) SIG_NAME M_D_DQ<1>
J 0
(-5440 1585);
DISPLAY 0.659574 (-5440 1585);
PAINT MONO (-5440 1585);
DISPLAY INVISIBLE (-5440 1585);
FORCEPROP 1 LASTPIN (-5450 1575) BN 1
J 0
(-5502 1583);
DISPLAY 0.617021 (-5502 1583);
PAINT PINK (-5502 1583);
FORCEPROP 2 LAST CDS_LIB mstr_standard
J 0
(-5500 1575);
PAINT MONO (-5500 1575);
DISPLAY INVISIBLE (-5500 1575);
FORCEPROP 1 LAST BODY_TYPE PLUMBING
J 0
(-5500 1525);
DISPLAY 1.595745 (-5500 1525);
PAINT GREEN (-5500 1525);
DISPLAY INVISIBLE (-5500 1525);
FORCEPROP 1 LAST HDL_TAP TRUE
J 0
(-5175 1450);
DISPLAY 1.595745 (-5175 1450);
PAINT GREEN (-5175 1450);
DISPLAY INVISIBLE (-5175 1450);
FORCEPROP 1 LAST PATH I22
J 0
(-5502 1575);
DISPLAY 0.872340 (-5502 1575);
PAINT GREEN (-5502 1575);
DISPLAY INVISIBLE (-5502 1575);
FORCEADD TAP..6
(-5500 1625);
FORCEPROP 3 LASTPIN (-5450 1625) SIG_NAME M_D_DQ<2>
J 0
(-5440 1635);
DISPLAY 0.659574 (-5440 1635);
PAINT MONO (-5440 1635);
DISPLAY INVISIBLE (-5440 1635);
FORCEPROP 1 LASTPIN (-5450 1625) BN 2
J 0
(-5502 1633);
DISPLAY 0.617021 (-5502 1633);
PAINT PINK (-5502 1633);
FORCEPROP 2 LAST CDS_LIB mstr_standard
J 0
(-5500 1625);
PAINT MONO (-5500 1625);
DISPLAY INVISIBLE (-5500 1625);
FORCEPROP 1 LAST BODY_TYPE PLUMBING
J 0
(-5500 1575);
DISPLAY 1.595745 (-5500 1575);
PAINT GREEN (-5500 1575);
DISPLAY INVISIBLE (-5500 1575);
FORCEPROP 1 LAST HDL_TAP TRUE
J 0
(-5175 1500);
DISPLAY 1.595745 (-5175 1500);
PAINT GREEN (-5175 1500);
DISPLAY INVISIBLE (-5175 1500);
FORCEPROP 1 LAST PATH I23
J 0
(-5502 1625);
DISPLAY 0.872340 (-5502 1625);
PAINT GREEN (-5502 1625);
DISPLAY INVISIBLE (-5502 1625);
FORCEADD TAP..6
(-5500 1675);
FORCEPROP 3 LASTPIN (-5450 1675) SIG_NAME M_D_DQ<3>
J 0
(-5440 1685);
DISPLAY 0.659574 (-5440 1685);
PAINT MONO (-5440 1685);
DISPLAY INVISIBLE (-5440 1685);
FORCEPROP 1 LASTPIN (-5450 1675) BN 3
J 0
(-5502 1683);
DISPLAY 0.617021 (-5502 1683);
PAINT PINK (-5502 1683);
FORCEPROP 2 LAST CDS_LIB mstr_standard
J 0
(-5500 1675);
PAINT MONO (-5500 1675);
DISPLAY INVISIBLE (-5500 1675);
FORCEPROP 1 LAST BODY_TYPE PLUMBING
J 0
(-5500 1625);
DISPLAY 1.595745 (-5500 1625);
PAINT GREEN (-5500 1625);
DISPLAY INVISIBLE (-5500 1625);
FORCEPROP 1 LAST HDL_TAP TRUE
J 0
(-5175 1550);
DISPLAY 1.595745 (-5175 1550);
PAINT GREEN (-5175 1550);
DISPLAY INVISIBLE (-5175 1550);
FORCEPROP 1 LAST PATH I24
J 0
(-5502 1675);
DISPLAY 0.872340 (-5502 1675);
PAINT GREEN (-5502 1675);
DISPLAY INVISIBLE (-5502 1675);
FORCEADD TAP..6
(-5500 1725);
FORCEPROP 3 LASTPIN (-5450 1725) SIG_NAME M_D_DQ<4>
J 0
(-5440 1735);
DISPLAY 0.659574 (-5440 1735);
PAINT MONO (-5440 1735);
DISPLAY INVISIBLE (-5440 1735);
FORCEPROP 1 LASTPIN (-5450 1725) BN 4
J 0
(-5502 1733);
DISPLAY 0.617021 (-5502 1733);
PAINT PINK (-5502 1733);
FORCEPROP 2 LAST CDS_LIB mstr_standard
J 0
(-5500 1725);
PAINT MONO (-5500 1725);
DISPLAY INVISIBLE (-5500 1725);
FORCEPROP 1 LAST BODY_TYPE PLUMBING
J 0
(-5500 1675);
DISPLAY 1.595745 (-5500 1675);
PAINT GREEN (-5500 1675);
DISPLAY INVISIBLE (-5500 1675);
FORCEPROP 1 LAST HDL_TAP TRUE
J 0
(-5175 1600);
DISPLAY 1.595745 (-5175 1600);
PAINT GREEN (-5175 1600);
DISPLAY INVISIBLE (-5175 1600);
FORCEPROP 1 LAST PATH I25
J 0
(-5502 1725);
DISPLAY 0.872340 (-5502 1725);
PAINT GREEN (-5502 1725);
DISPLAY INVISIBLE (-5502 1725);
FORCEADD TAP..6
(-5500 1775);
FORCEPROP 3 LASTPIN (-5450 1775) SIG_NAME M_D_DQ<5>
J 0
(-5440 1785);
DISPLAY 0.659574 (-5440 1785);
PAINT MONO (-5440 1785);
DISPLAY INVISIBLE (-5440 1785);
FORCEPROP 1 LASTPIN (-5450 1775) BN 5
J 0
(-5502 1783);
DISPLAY 0.617021 (-5502 1783);
PAINT PINK (-5502 1783);
FORCEPROP 2 LAST CDS_LIB mstr_standard
J 0
(-5500 1775);
PAINT MONO (-5500 1775);
DISPLAY INVISIBLE (-5500 1775);
FORCEPROP 1 LAST BODY_TYPE PLUMBING
J 0
(-5500 1725);
DISPLAY 1.595745 (-5500 1725);
PAINT GREEN (-5500 1725);
DISPLAY INVISIBLE (-5500 1725);
FORCEPROP 1 LAST HDL_TAP TRUE
J 0
(-5175 1650);
DISPLAY 1.595745 (-5175 1650);
PAINT GREEN (-5175 1650);
DISPLAY INVISIBLE (-5175 1650);
FORCEPROP 1 LAST PATH I26
J 0
(-5502 1775);
DISPLAY 0.872340 (-5502 1775);
PAINT GREEN (-5502 1775);
DISPLAY INVISIBLE (-5502 1775);
FORCEADD TAP..6
(-5500 1825);
FORCEPROP 3 LASTPIN (-5450 1825) SIG_NAME M_D_DQ<6>
J 0
(-5440 1835);
DISPLAY 0.659574 (-5440 1835);
PAINT MONO (-5440 1835);
DISPLAY INVISIBLE (-5440 1835);
FORCEPROP 1 LASTPIN (-5450 1825) BN 6
J 0
(-5502 1833);
DISPLAY 0.617021 (-5502 1833);
PAINT PINK (-5502 1833);
FORCEPROP 2 LAST CDS_LIB mstr_standard
J 0
(-5500 1825);
PAINT MONO (-5500 1825);
DISPLAY INVISIBLE (-5500 1825);
FORCEPROP 1 LAST BODY_TYPE PLUMBING
J 0
(-5500 1775);
DISPLAY 1.595745 (-5500 1775);
PAINT GREEN (-5500 1775);
DISPLAY INVISIBLE (-5500 1775);
FORCEPROP 1 LAST HDL_TAP TRUE
J 0
(-5175 1700);
DISPLAY 1.595745 (-5175 1700);
PAINT GREEN (-5175 1700);
DISPLAY INVISIBLE (-5175 1700);
FORCEPROP 1 LAST PATH I27
J 0
(-5502 1825);
DISPLAY 0.872340 (-5502 1825);
PAINT GREEN (-5502 1825);
DISPLAY INVISIBLE (-5502 1825);
FORCEADD TAP..6
(-5500 1925);
FORCEPROP 3 LASTPIN (-5450 1925) SIG_NAME M_D_DQ<8>
J 0
(-5440 1935);
DISPLAY 0.659574 (-5440 1935);
PAINT MONO (-5440 1935);
DISPLAY INVISIBLE (-5440 1935);
FORCEPROP 1 LASTPIN (-5450 1925) BN 8
J 0
(-5502 1933);
DISPLAY 0.617021 (-5502 1933);
PAINT PINK (-5502 1933);
FORCEPROP 2 LAST CDS_LIB mstr_standard
J 0
(-5500 1925);
PAINT MONO (-5500 1925);
DISPLAY INVISIBLE (-5500 1925);
FORCEPROP 1 LAST BODY_TYPE PLUMBING
J 0
(-5500 1875);
DISPLAY 1.595745 (-5500 1875);
PAINT GREEN (-5500 1875);
DISPLAY INVISIBLE (-5500 1875);
FORCEPROP 1 LAST HDL_TAP TRUE
J 0
(-5175 1800);
DISPLAY 1.595745 (-5175 1800);
PAINT GREEN (-5175 1800);
DISPLAY INVISIBLE (-5175 1800);
FORCEPROP 1 LAST PATH I28
J 0
(-5502 1925);
DISPLAY 0.872340 (-5502 1925);
PAINT GREEN (-5502 1925);
DISPLAY INVISIBLE (-5502 1925);
FORCEADD TAP..6
(-5500 1875);
FORCEPROP 3 LASTPIN (-5450 1875) SIG_NAME M_D_DQ<7>
J 0
(-5440 1885);
DISPLAY 0.659574 (-5440 1885);
PAINT MONO (-5440 1885);
DISPLAY INVISIBLE (-5440 1885);
FORCEPROP 1 LASTPIN (-5450 1875) BN 7
J 0
(-5502 1883);
DISPLAY 0.617021 (-5502 1883);
PAINT PINK (-5502 1883);
FORCEPROP 2 LAST CDS_LIB mstr_standard
J 0
(-5500 1875);
PAINT MONO (-5500 1875);
DISPLAY INVISIBLE (-5500 1875);
FORCEPROP 1 LAST BODY_TYPE PLUMBING
J 0
(-5500 1825);
DISPLAY 1.595745 (-5500 1825);
PAINT GREEN (-5500 1825);
DISPLAY INVISIBLE (-5500 1825);
FORCEPROP 1 LAST HDL_TAP TRUE
J 0
(-5175 1750);
DISPLAY 1.595745 (-5175 1750);
PAINT GREEN (-5175 1750);
DISPLAY INVISIBLE (-5175 1750);
FORCEPROP 1 LAST PATH I29
J 0
(-5502 1875);
DISPLAY 0.872340 (-5502 1875);
PAINT GREEN (-5502 1875);
DISPLAY INVISIBLE (-5502 1875);
FORCEADD OFFPAGE..5
(-6350 1025);
FORCEPROP 2 LAST $XR0 49 
J 0
(-6574 1025);
DISPLAY 0.638298 (-6574 1025);
PAINT MONO (-6574 1025);
FORCEPROP 2 LAST $XR1 50 
J 0
(-6664 1025);
DISPLAY 0.638298 (-6664 1025);
PAINT MONO (-6664 1025);
FORCEPROP 2 LAST CDS_LIB mstr_standard
J 0
(-6350 1025);
PAINT MONO (-6350 1025);
DISPLAY INVISIBLE (-6350 1025);
FORCEPROP 1 LAST OFFPAGE TRUE
J 0
(-6025 900);
DISPLAY 1.170213 (-6025 900);
PAINT GREEN (-6025 900);
DISPLAY INVISIBLE (-6025 900);
FORCEPROP 1 LAST COMMENT_BODY TRUE
J 0
(-6250 950);
DISPLAY 1.170213 (-6250 950);
PAINT GREEN (-6250 950);
DISPLAY INVISIBLE (-6250 950);
FORCEPROP 2 LAST PATH I3
J 0
(-6300 1100);
DISPLAY 1.021277 (-6300 1100);
PAINT ORANGE (-6300 1100);
DISPLAY INVISIBLE (-6300 1100);
FORCEADD TAP..6
(-5500 1975);
FORCEPROP 3 LASTPIN (-5450 1975) SIG_NAME M_D_DQ<9>
J 0
(-5440 1985);
DISPLAY 0.659574 (-5440 1985);
PAINT MONO (-5440 1985);
DISPLAY INVISIBLE (-5440 1985);
FORCEPROP 1 LASTPIN (-5450 1975) BN 9
J 0
(-5502 1983);
DISPLAY 0.617021 (-5502 1983);
PAINT PINK (-5502 1983);
FORCEPROP 2 LAST CDS_LIB mstr_standard
J 0
(-5500 1975);
PAINT MONO (-5500 1975);
DISPLAY INVISIBLE (-5500 1975);
FORCEPROP 1 LAST BODY_TYPE PLUMBING
J 0
(-5500 1925);
DISPLAY 1.595745 (-5500 1925);
PAINT GREEN (-5500 1925);
DISPLAY INVISIBLE (-5500 1925);
FORCEPROP 1 LAST HDL_TAP TRUE
J 0
(-5175 1850);
DISPLAY 1.595745 (-5175 1850);
PAINT GREEN (-5175 1850);
DISPLAY INVISIBLE (-5175 1850);
FORCEPROP 1 LAST PATH I31
J 0
(-5502 1975);
DISPLAY 0.872340 (-5502 1975);
PAINT GREEN (-5502 1975);
DISPLAY INVISIBLE (-5502 1975);
FORCEADD TAP..6
(-5500 2025);
FORCEPROP 3 LASTPIN (-5450 2025) SIG_NAME M_D_DQ<10>
J 0
(-5440 2035);
DISPLAY 0.659574 (-5440 2035);
PAINT MONO (-5440 2035);
DISPLAY INVISIBLE (-5440 2035);
FORCEPROP 1 LASTPIN (-5450 2025) BN 10
J 0
(-5502 2033);
DISPLAY 0.617021 (-5502 2033);
PAINT PINK (-5502 2033);
FORCEPROP 2 LAST CDS_LIB mstr_standard
J 0
(-5500 2025);
PAINT MONO (-5500 2025);
DISPLAY INVISIBLE (-5500 2025);
FORCEPROP 1 LAST BODY_TYPE PLUMBING
J 0
(-5500 1975);
DISPLAY 1.595745 (-5500 1975);
PAINT GREEN (-5500 1975);
DISPLAY INVISIBLE (-5500 1975);
FORCEPROP 1 LAST HDL_TAP TRUE
J 0
(-5175 1900);
DISPLAY 1.595745 (-5175 1900);
PAINT GREEN (-5175 1900);
DISPLAY INVISIBLE (-5175 1900);
FORCEPROP 1 LAST PATH I32
J 0
(-5502 2025);
DISPLAY 0.872340 (-5502 2025);
PAINT GREEN (-5502 2025);
DISPLAY INVISIBLE (-5502 2025);
FORCEADD TAP..6
(-5500 2075);
FORCEPROP 3 LASTPIN (-5450 2075) SIG_NAME M_D_DQ<11>
J 0
(-5440 2085);
DISPLAY 0.659574 (-5440 2085);
PAINT MONO (-5440 2085);
DISPLAY INVISIBLE (-5440 2085);
FORCEPROP 1 LASTPIN (-5450 2075) BN 11
J 0
(-5502 2083);
DISPLAY 0.617021 (-5502 2083);
PAINT PINK (-5502 2083);
FORCEPROP 2 LAST CDS_LIB mstr_standard
J 0
(-5500 2075);
PAINT MONO (-5500 2075);
DISPLAY INVISIBLE (-5500 2075);
FORCEPROP 1 LAST BODY_TYPE PLUMBING
J 0
(-5500 2025);
DISPLAY 1.595745 (-5500 2025);
PAINT GREEN (-5500 2025);
DISPLAY INVISIBLE (-5500 2025);
FORCEPROP 1 LAST HDL_TAP TRUE
J 0
(-5175 1950);
DISPLAY 1.595745 (-5175 1950);
PAINT GREEN (-5175 1950);
DISPLAY INVISIBLE (-5175 1950);
FORCEPROP 1 LAST PATH I33
J 0
(-5502 2075);
DISPLAY 0.872340 (-5502 2075);
PAINT GREEN (-5502 2075);
DISPLAY INVISIBLE (-5502 2075);
FORCEADD TAP..6
(-5500 2125);
FORCEPROP 3 LASTPIN (-5450 2125) SIG_NAME M_D_DQ<12>
J 0
(-5440 2135);
DISPLAY 0.659574 (-5440 2135);
PAINT MONO (-5440 2135);
DISPLAY INVISIBLE (-5440 2135);
FORCEPROP 1 LASTPIN (-5450 2125) BN 12
J 0
(-5502 2133);
DISPLAY 0.617021 (-5502 2133);
PAINT PINK (-5502 2133);
FORCEPROP 2 LAST CDS_LIB mstr_standard
J 0
(-5500 2125);
PAINT MONO (-5500 2125);
DISPLAY INVISIBLE (-5500 2125);
FORCEPROP 1 LAST BODY_TYPE PLUMBING
J 0
(-5500 2075);
DISPLAY 1.595745 (-5500 2075);
PAINT GREEN (-5500 2075);
DISPLAY INVISIBLE (-5500 2075);
FORCEPROP 1 LAST HDL_TAP TRUE
J 0
(-5175 2000);
DISPLAY 1.595745 (-5175 2000);
PAINT GREEN (-5175 2000);
DISPLAY INVISIBLE (-5175 2000);
FORCEPROP 1 LAST PATH I34
J 0
(-5502 2125);
DISPLAY 0.872340 (-5502 2125);
PAINT GREEN (-5502 2125);
DISPLAY INVISIBLE (-5502 2125);
FORCEADD TAP..6
(-5500 2175);
FORCEPROP 3 LASTPIN (-5450 2175) SIG_NAME M_D_DQ<13>
J 0
(-5440 2185);
DISPLAY 0.659574 (-5440 2185);
PAINT MONO (-5440 2185);
DISPLAY INVISIBLE (-5440 2185);
FORCEPROP 1 LASTPIN (-5450 2175) BN 13
J 0
(-5502 2183);
DISPLAY 0.617021 (-5502 2183);
PAINT PINK (-5502 2183);
FORCEPROP 2 LAST CDS_LIB mstr_standard
J 0
(-5500 2175);
PAINT MONO (-5500 2175);
DISPLAY INVISIBLE (-5500 2175);
FORCEPROP 1 LAST BODY_TYPE PLUMBING
J 0
(-5500 2125);
DISPLAY 1.595745 (-5500 2125);
PAINT GREEN (-5500 2125);
DISPLAY INVISIBLE (-5500 2125);
FORCEPROP 1 LAST HDL_TAP TRUE
J 0
(-5175 2050);
DISPLAY 1.595745 (-5175 2050);
PAINT GREEN (-5175 2050);
DISPLAY INVISIBLE (-5175 2050);
FORCEPROP 1 LAST PATH I35
J 0
(-5502 2175);
DISPLAY 0.872340 (-5502 2175);
PAINT GREEN (-5502 2175);
DISPLAY INVISIBLE (-5502 2175);
FORCEADD TAP..6
(-5500 2225);
FORCEPROP 3 LASTPIN (-5450 2225) SIG_NAME M_D_DQ<14>
J 0
(-5440 2235);
DISPLAY 0.659574 (-5440 2235);
PAINT MONO (-5440 2235);
DISPLAY INVISIBLE (-5440 2235);
FORCEPROP 1 LASTPIN (-5450 2225) BN 14
J 0
(-5502 2233);
DISPLAY 0.617021 (-5502 2233);
PAINT PINK (-5502 2233);
FORCEPROP 2 LAST CDS_LIB mstr_standard
J 0
(-5500 2225);
PAINT MONO (-5500 2225);
DISPLAY INVISIBLE (-5500 2225);
FORCEPROP 1 LAST BODY_TYPE PLUMBING
J 0
(-5500 2175);
DISPLAY 1.595745 (-5500 2175);
PAINT GREEN (-5500 2175);
DISPLAY INVISIBLE (-5500 2175);
FORCEPROP 1 LAST HDL_TAP TRUE
J 0
(-5175 2100);
DISPLAY 1.595745 (-5175 2100);
PAINT GREEN (-5175 2100);
DISPLAY INVISIBLE (-5175 2100);
FORCEPROP 1 LAST PATH I36
J 0
(-5502 2225);
DISPLAY 0.872340 (-5502 2225);
PAINT GREEN (-5502 2225);
DISPLAY INVISIBLE (-5502 2225);
FORCEADD TAP..6
(-5500 2275);
FORCEPROP 3 LASTPIN (-5450 2275) SIG_NAME M_D_DQ<15>
J 0
(-5440 2285);
DISPLAY 0.659574 (-5440 2285);
PAINT MONO (-5440 2285);
DISPLAY INVISIBLE (-5440 2285);
FORCEPROP 1 LASTPIN (-5450 2275) BN 15
J 0
(-5502 2283);
DISPLAY 0.617021 (-5502 2283);
PAINT PINK (-5502 2283);
FORCEPROP 2 LAST CDS_LIB mstr_standard
J 0
(-5500 2275);
PAINT MONO (-5500 2275);
DISPLAY INVISIBLE (-5500 2275);
FORCEPROP 1 LAST BODY_TYPE PLUMBING
J 0
(-5500 2225);
DISPLAY 1.595745 (-5500 2225);
PAINT GREEN (-5500 2225);
DISPLAY INVISIBLE (-5500 2225);
FORCEPROP 1 LAST HDL_TAP TRUE
J 0
(-5175 2150);
DISPLAY 1.595745 (-5175 2150);
PAINT GREEN (-5175 2150);
DISPLAY INVISIBLE (-5175 2150);
FORCEPROP 1 LAST PATH I37
J 0
(-5502 2275);
DISPLAY 0.872340 (-5502 2275);
PAINT GREEN (-5502 2275);
DISPLAY INVISIBLE (-5502 2275);
FORCEADD TAP..6
(-5500 2325);
FORCEPROP 3 LASTPIN (-5450 2325) SIG_NAME M_D_DQ<16>
J 0
(-5440 2335);
DISPLAY 0.659574 (-5440 2335);
PAINT MONO (-5440 2335);
DISPLAY INVISIBLE (-5440 2335);
FORCEPROP 1 LASTPIN (-5450 2325) BN 16
J 0
(-5502 2333);
DISPLAY 0.617021 (-5502 2333);
PAINT PINK (-5502 2333);
FORCEPROP 2 LAST CDS_LIB mstr_standard
J 0
(-5500 2325);
PAINT MONO (-5500 2325);
DISPLAY INVISIBLE (-5500 2325);
FORCEPROP 1 LAST BODY_TYPE PLUMBING
J 0
(-5500 2275);
DISPLAY 1.595745 (-5500 2275);
PAINT GREEN (-5500 2275);
DISPLAY INVISIBLE (-5500 2275);
FORCEPROP 1 LAST HDL_TAP TRUE
J 0
(-5175 2200);
DISPLAY 1.595745 (-5175 2200);
PAINT GREEN (-5175 2200);
DISPLAY INVISIBLE (-5175 2200);
FORCEPROP 1 LAST PATH I38
J 0
(-5502 2325);
DISPLAY 0.872340 (-5502 2325);
PAINT GREEN (-5502 2325);
DISPLAY INVISIBLE (-5502 2325);
FORCEADD TAP..6
(-5500 2375);
FORCEPROP 3 LASTPIN (-5450 2375) SIG_NAME M_D_DQ<17>
J 0
(-5440 2385);
DISPLAY 0.659574 (-5440 2385);
PAINT MONO (-5440 2385);
DISPLAY INVISIBLE (-5440 2385);
FORCEPROP 1 LASTPIN (-5450 2375) BN 17
J 0
(-5502 2383);
DISPLAY 0.617021 (-5502 2383);
PAINT PINK (-5502 2383);
FORCEPROP 2 LAST CDS_LIB mstr_standard
J 0
(-5500 2375);
PAINT MONO (-5500 2375);
DISPLAY INVISIBLE (-5500 2375);
FORCEPROP 1 LAST BODY_TYPE PLUMBING
J 0
(-5500 2325);
DISPLAY 1.595745 (-5500 2325);
PAINT GREEN (-5500 2325);
DISPLAY INVISIBLE (-5500 2325);
FORCEPROP 1 LAST HDL_TAP TRUE
J 0
(-5175 2250);
DISPLAY 1.595745 (-5175 2250);
PAINT GREEN (-5175 2250);
DISPLAY INVISIBLE (-5175 2250);
FORCEPROP 1 LAST PATH I39
J 0
(-5502 2375);
DISPLAY 0.872340 (-5502 2375);
PAINT GREEN (-5502 2375);
DISPLAY INVISIBLE (-5502 2375);
FORCEADD OFFPAGE..6
(-6350 1475);
FORCEPROP 2 LAST $XR0 49 
J 0
(-6629 1475);
DISPLAY 0.638298 (-6629 1475);
PAINT MONO (-6629 1475);
FORCEPROP 2 LAST $XR1 50 
J 0
(-6719 1475);
DISPLAY 0.638298 (-6719 1475);
PAINT MONO (-6719 1475);
FORCEPROP 2 LAST CDS_LIB mstr_standard
J 0
(-6350 1475);
PAINT MONO (-6350 1475);
DISPLAY INVISIBLE (-6350 1475);
FORCEPROP 1 LAST OFFPAGE TRUE
J 0
(-6025 1350);
DISPLAY 1.170213 (-6025 1350);
PAINT GREEN (-6025 1350);
DISPLAY INVISIBLE (-6025 1350);
FORCEPROP 1 LAST COMMENT_BODY TRUE
J 0
(-6250 1400);
DISPLAY 1.170213 (-6250 1400);
PAINT GREEN (-6250 1400);
DISPLAY INVISIBLE (-6250 1400);
FORCEPROP 2 LAST PATH I4
J 0
(-6300 1550);
DISPLAY 1.021277 (-6300 1550);
PAINT ORANGE (-6300 1550);
DISPLAY INVISIBLE (-6300 1550);
FORCEADD TAP..6
(-5500 2425);
FORCEPROP 3 LASTPIN (-5450 2425) SIG_NAME M_D_DQ<18>
J 0
(-5440 2435);
DISPLAY 0.659574 (-5440 2435);
PAINT MONO (-5440 2435);
DISPLAY INVISIBLE (-5440 2435);
FORCEPROP 1 LASTPIN (-5450 2425) BN 18
J 0
(-5502 2433);
DISPLAY 0.617021 (-5502 2433);
PAINT PINK (-5502 2433);
FORCEPROP 2 LAST CDS_LIB mstr_standard
J 0
(-5500 2425);
PAINT MONO (-5500 2425);
DISPLAY INVISIBLE (-5500 2425);
FORCEPROP 1 LAST BODY_TYPE PLUMBING
J 0
(-5500 2375);
DISPLAY 1.595745 (-5500 2375);
PAINT GREEN (-5500 2375);
DISPLAY INVISIBLE (-5500 2375);
FORCEPROP 1 LAST HDL_TAP TRUE
J 0
(-5175 2300);
DISPLAY 1.595745 (-5175 2300);
PAINT GREEN (-5175 2300);
DISPLAY INVISIBLE (-5175 2300);
FORCEPROP 1 LAST PATH I40
J 0
(-5502 2425);
DISPLAY 0.872340 (-5502 2425);
PAINT GREEN (-5502 2425);
DISPLAY INVISIBLE (-5502 2425);
FORCEADD TAP..6
(-5500 2475);
FORCEPROP 3 LASTPIN (-5450 2475) SIG_NAME M_D_DQ<19>
J 0
(-5440 2485);
DISPLAY 0.659574 (-5440 2485);
PAINT MONO (-5440 2485);
DISPLAY INVISIBLE (-5440 2485);
FORCEPROP 1 LASTPIN (-5450 2475) BN 19
J 0
(-5502 2483);
DISPLAY 0.617021 (-5502 2483);
PAINT PINK (-5502 2483);
FORCEPROP 2 LAST CDS_LIB mstr_standard
J 0
(-5500 2475);
PAINT MONO (-5500 2475);
DISPLAY INVISIBLE (-5500 2475);
FORCEPROP 1 LAST BODY_TYPE PLUMBING
J 0
(-5500 2425);
DISPLAY 1.595745 (-5500 2425);
PAINT GREEN (-5500 2425);
DISPLAY INVISIBLE (-5500 2425);
FORCEPROP 1 LAST HDL_TAP TRUE
J 0
(-5175 2350);
DISPLAY 1.595745 (-5175 2350);
PAINT GREEN (-5175 2350);
DISPLAY INVISIBLE (-5175 2350);
FORCEPROP 1 LAST PATH I41
J 0
(-5502 2475);
DISPLAY 0.872340 (-5502 2475);
PAINT GREEN (-5502 2475);
DISPLAY INVISIBLE (-5502 2475);
FORCEADD TAP..6
(-5500 2525);
FORCEPROP 3 LASTPIN (-5450 2525) SIG_NAME M_D_DQ<20>
J 0
(-5440 2535);
DISPLAY 0.659574 (-5440 2535);
PAINT MONO (-5440 2535);
DISPLAY INVISIBLE (-5440 2535);
FORCEPROP 1 LASTPIN (-5450 2525) BN 20
J 0
(-5502 2533);
DISPLAY 0.617021 (-5502 2533);
PAINT PINK (-5502 2533);
FORCEPROP 2 LAST CDS_LIB mstr_standard
J 0
(-5500 2525);
PAINT MONO (-5500 2525);
DISPLAY INVISIBLE (-5500 2525);
FORCEPROP 1 LAST BODY_TYPE PLUMBING
J 0
(-5500 2475);
DISPLAY 1.595745 (-5500 2475);
PAINT GREEN (-5500 2475);
DISPLAY INVISIBLE (-5500 2475);
FORCEPROP 1 LAST HDL_TAP TRUE
J 0
(-5175 2400);
DISPLAY 1.595745 (-5175 2400);
PAINT GREEN (-5175 2400);
DISPLAY INVISIBLE (-5175 2400);
FORCEPROP 1 LAST PATH I42
J 0
(-5502 2525);
DISPLAY 0.872340 (-5502 2525);
PAINT GREEN (-5502 2525);
DISPLAY INVISIBLE (-5502 2525);
FORCEADD TAP..6
(-5500 2575);
FORCEPROP 3 LASTPIN (-5450 2575) SIG_NAME M_D_DQ<21>
J 0
(-5440 2585);
DISPLAY 0.659574 (-5440 2585);
PAINT MONO (-5440 2585);
DISPLAY INVISIBLE (-5440 2585);
FORCEPROP 1 LASTPIN (-5450 2575) BN 21
J 0
(-5502 2583);
DISPLAY 0.617021 (-5502 2583);
PAINT PINK (-5502 2583);
FORCEPROP 2 LAST CDS_LIB mstr_standard
J 0
(-5500 2575);
PAINT MONO (-5500 2575);
DISPLAY INVISIBLE (-5500 2575);
FORCEPROP 1 LAST BODY_TYPE PLUMBING
J 0
(-5500 2525);
DISPLAY 1.595745 (-5500 2525);
PAINT GREEN (-5500 2525);
DISPLAY INVISIBLE (-5500 2525);
FORCEPROP 1 LAST HDL_TAP TRUE
J 0
(-5175 2450);
DISPLAY 1.595745 (-5175 2450);
PAINT GREEN (-5175 2450);
DISPLAY INVISIBLE (-5175 2450);
FORCEPROP 1 LAST PATH I43
J 0
(-5502 2575);
DISPLAY 0.872340 (-5502 2575);
PAINT GREEN (-5502 2575);
DISPLAY INVISIBLE (-5502 2575);
FORCEADD TAP..6
(-5500 2625);
FORCEPROP 3 LASTPIN (-5450 2625) SIG_NAME M_D_DQ<22>
J 0
(-5440 2635);
DISPLAY 0.659574 (-5440 2635);
PAINT MONO (-5440 2635);
DISPLAY INVISIBLE (-5440 2635);
FORCEPROP 1 LASTPIN (-5450 2625) BN 22
J 0
(-5502 2633);
DISPLAY 0.617021 (-5502 2633);
PAINT PINK (-5502 2633);
FORCEPROP 2 LAST CDS_LIB mstr_standard
J 0
(-5500 2625);
PAINT MONO (-5500 2625);
DISPLAY INVISIBLE (-5500 2625);
FORCEPROP 1 LAST BODY_TYPE PLUMBING
J 0
(-5500 2575);
DISPLAY 1.595745 (-5500 2575);
PAINT GREEN (-5500 2575);
DISPLAY INVISIBLE (-5500 2575);
FORCEPROP 1 LAST HDL_TAP TRUE
J 0
(-5175 2500);
DISPLAY 1.595745 (-5175 2500);
PAINT GREEN (-5175 2500);
DISPLAY INVISIBLE (-5175 2500);
FORCEPROP 1 LAST PATH I44
J 0
(-5502 2625);
DISPLAY 0.872340 (-5502 2625);
PAINT GREEN (-5502 2625);
DISPLAY INVISIBLE (-5502 2625);
FORCEADD TAP..6
(-5500 2675);
FORCEPROP 3 LASTPIN (-5450 2675) SIG_NAME M_D_DQ<23>
J 0
(-5440 2685);
DISPLAY 0.659574 (-5440 2685);
PAINT MONO (-5440 2685);
DISPLAY INVISIBLE (-5440 2685);
FORCEPROP 1 LASTPIN (-5450 2675) BN 23
J 0
(-5502 2683);
DISPLAY 0.617021 (-5502 2683);
PAINT PINK (-5502 2683);
FORCEPROP 2 LAST CDS_LIB mstr_standard
J 0
(-5500 2675);
PAINT MONO (-5500 2675);
DISPLAY INVISIBLE (-5500 2675);
FORCEPROP 1 LAST BODY_TYPE PLUMBING
J 0
(-5500 2625);
DISPLAY 1.595745 (-5500 2625);
PAINT GREEN (-5500 2625);
DISPLAY INVISIBLE (-5500 2625);
FORCEPROP 1 LAST HDL_TAP TRUE
J 0
(-5175 2550);
DISPLAY 1.595745 (-5175 2550);
PAINT GREEN (-5175 2550);
DISPLAY INVISIBLE (-5175 2550);
FORCEPROP 1 LAST PATH I45
J 0
(-5502 2675);
DISPLAY 0.872340 (-5502 2675);
PAINT GREEN (-5502 2675);
DISPLAY INVISIBLE (-5502 2675);
FORCEADD TAP..6
(-5500 2725);
FORCEPROP 3 LASTPIN (-5450 2725) SIG_NAME M_D_DQ<24>
J 0
(-5440 2735);
DISPLAY 0.659574 (-5440 2735);
PAINT MONO (-5440 2735);
DISPLAY INVISIBLE (-5440 2735);
FORCEPROP 1 LASTPIN (-5450 2725) BN 24
J 0
(-5502 2733);
DISPLAY 0.617021 (-5502 2733);
PAINT PINK (-5502 2733);
FORCEPROP 2 LAST CDS_LIB mstr_standard
J 0
(-5500 2725);
PAINT MONO (-5500 2725);
DISPLAY INVISIBLE (-5500 2725);
FORCEPROP 1 LAST BODY_TYPE PLUMBING
J 0
(-5500 2675);
DISPLAY 1.595745 (-5500 2675);
PAINT GREEN (-5500 2675);
DISPLAY INVISIBLE (-5500 2675);
FORCEPROP 1 LAST HDL_TAP TRUE
J 0
(-5175 2600);
DISPLAY 1.595745 (-5175 2600);
PAINT GREEN (-5175 2600);
DISPLAY INVISIBLE (-5175 2600);
FORCEPROP 1 LAST PATH I46
J 0
(-5502 2725);
DISPLAY 0.872340 (-5502 2725);
PAINT GREEN (-5502 2725);
DISPLAY INVISIBLE (-5502 2725);
FORCEADD TAP..6
(-5500 2825);
FORCEPROP 3 LASTPIN (-5450 2825) SIG_NAME M_D_DQ<26>
J 0
(-5440 2835);
DISPLAY 0.659574 (-5440 2835);
PAINT MONO (-5440 2835);
DISPLAY INVISIBLE (-5440 2835);
FORCEPROP 1 LASTPIN (-5450 2825) BN 26
J 0
(-5502 2833);
DISPLAY 0.617021 (-5502 2833);
PAINT PINK (-5502 2833);
FORCEPROP 2 LAST CDS_LIB mstr_standard
J 0
(-5500 2825);
PAINT MONO (-5500 2825);
DISPLAY INVISIBLE (-5500 2825);
FORCEPROP 1 LAST BODY_TYPE PLUMBING
J 0
(-5500 2775);
DISPLAY 1.595745 (-5500 2775);
PAINT GREEN (-5500 2775);
DISPLAY INVISIBLE (-5500 2775);
FORCEPROP 1 LAST HDL_TAP TRUE
J 0
(-5175 2700);
DISPLAY 1.595745 (-5175 2700);
PAINT GREEN (-5175 2700);
DISPLAY INVISIBLE (-5175 2700);
FORCEPROP 1 LAST PATH I47
J 0
(-5502 2825);
DISPLAY 0.872340 (-5502 2825);
PAINT GREEN (-5502 2825);
DISPLAY INVISIBLE (-5502 2825);
FORCEADD TAP..6
(-5500 2775);
FORCEPROP 3 LASTPIN (-5450 2775) SIG_NAME M_D_DQ<25>
J 0
(-5440 2785);
DISPLAY 0.659574 (-5440 2785);
PAINT MONO (-5440 2785);
DISPLAY INVISIBLE (-5440 2785);
FORCEPROP 1 LASTPIN (-5450 2775) BN 25
J 0
(-5502 2783);
DISPLAY 0.617021 (-5502 2783);
PAINT PINK (-5502 2783);
FORCEPROP 2 LAST CDS_LIB mstr_standard
J 0
(-5500 2775);
PAINT MONO (-5500 2775);
DISPLAY INVISIBLE (-5500 2775);
FORCEPROP 1 LAST BODY_TYPE PLUMBING
J 0
(-5500 2725);
DISPLAY 1.595745 (-5500 2725);
PAINT GREEN (-5500 2725);
DISPLAY INVISIBLE (-5500 2725);
FORCEPROP 1 LAST HDL_TAP TRUE
J 0
(-5175 2650);
DISPLAY 1.595745 (-5175 2650);
PAINT GREEN (-5175 2650);
DISPLAY INVISIBLE (-5175 2650);
FORCEPROP 1 LAST PATH I48
J 0
(-5502 2775);
DISPLAY 0.872340 (-5502 2775);
PAINT GREEN (-5502 2775);
DISPLAY INVISIBLE (-5502 2775);
FORCEADD TAP..6
(-5500 2875);
FORCEPROP 3 LASTPIN (-5450 2875) SIG_NAME M_D_DQ<27>
J 0
(-5440 2885);
DISPLAY 0.659574 (-5440 2885);
PAINT MONO (-5440 2885);
DISPLAY INVISIBLE (-5440 2885);
FORCEPROP 1 LASTPIN (-5450 2875) BN 27
J 0
(-5502 2883);
DISPLAY 0.617021 (-5502 2883);
PAINT PINK (-5502 2883);
FORCEPROP 2 LAST CDS_LIB mstr_standard
J 0
(-5500 2875);
PAINT MONO (-5500 2875);
DISPLAY INVISIBLE (-5500 2875);
FORCEPROP 1 LAST BODY_TYPE PLUMBING
J 0
(-5500 2825);
DISPLAY 1.595745 (-5500 2825);
PAINT GREEN (-5500 2825);
DISPLAY INVISIBLE (-5500 2825);
FORCEPROP 1 LAST HDL_TAP TRUE
J 0
(-5175 2750);
DISPLAY 1.595745 (-5175 2750);
PAINT GREEN (-5175 2750);
DISPLAY INVISIBLE (-5175 2750);
FORCEPROP 1 LAST PATH I49
J 0
(-5502 2875);
DISPLAY 0.872340 (-5502 2875);
PAINT GREEN (-5502 2875);
DISPLAY INVISIBLE (-5502 2875);
FORCEADD TAP..6
(-5500 625);
FORCEPROP 3 LASTPIN (-5450 625) SIG_NAME M_D_CLK_DN<0>
J 0
(-5440 635);
DISPLAY 0.659574 (-5440 635);
PAINT MONO (-5440 635);
DISPLAY INVISIBLE (-5440 635);
FORCEPROP 1 LASTPIN (-5450 625) BN 0
J 0
(-5502 633);
DISPLAY 0.617021 (-5502 633);
PAINT PINK (-5502 633);
FORCEPROP 2 LAST CDS_LIB mstr_standard
J 0
(-5500 625);
PAINT MONO (-5500 625);
DISPLAY INVISIBLE (-5500 625);
FORCEPROP 1 LAST BODY_TYPE PLUMBING
J 0
(-5500 575);
DISPLAY 1.595745 (-5500 575);
PAINT GREEN (-5500 575);
DISPLAY INVISIBLE (-5500 575);
FORCEPROP 1 LAST HDL_TAP TRUE
J 0
(-5175 500);
DISPLAY 1.595745 (-5175 500);
PAINT GREEN (-5175 500);
DISPLAY INVISIBLE (-5175 500);
FORCEPROP 1 LAST PATH I5
J 0
(-5502 625);
DISPLAY 0.872340 (-5502 625);
PAINT GREEN (-5502 625);
DISPLAY INVISIBLE (-5502 625);
FORCEADD TAP..6
(-5500 2925);
FORCEPROP 3 LASTPIN (-5450 2925) SIG_NAME M_D_DQ<28>
J 0
(-5440 2935);
DISPLAY 0.659574 (-5440 2935);
PAINT MONO (-5440 2935);
DISPLAY INVISIBLE (-5440 2935);
FORCEPROP 1 LASTPIN (-5450 2925) BN 28
J 0
(-5502 2933);
DISPLAY 0.617021 (-5502 2933);
PAINT PINK (-5502 2933);
FORCEPROP 2 LAST CDS_LIB mstr_standard
J 0
(-5500 2925);
PAINT MONO (-5500 2925);
DISPLAY INVISIBLE (-5500 2925);
FORCEPROP 1 LAST BODY_TYPE PLUMBING
J 0
(-5500 2875);
DISPLAY 1.595745 (-5500 2875);
PAINT GREEN (-5500 2875);
DISPLAY INVISIBLE (-5500 2875);
FORCEPROP 1 LAST HDL_TAP TRUE
J 0
(-5175 2800);
DISPLAY 1.595745 (-5175 2800);
PAINT GREEN (-5175 2800);
DISPLAY INVISIBLE (-5175 2800);
FORCEPROP 1 LAST PATH I50
J 0
(-5502 2925);
DISPLAY 0.872340 (-5502 2925);
PAINT GREEN (-5502 2925);
DISPLAY INVISIBLE (-5502 2925);
FORCEADD TAP..6
(-5500 2975);
FORCEPROP 3 LASTPIN (-5450 2975) SIG_NAME M_D_DQ<29>
J 0
(-5440 2985);
DISPLAY 0.659574 (-5440 2985);
PAINT MONO (-5440 2985);
DISPLAY INVISIBLE (-5440 2985);
FORCEPROP 1 LASTPIN (-5450 2975) BN 29
J 0
(-5502 2983);
DISPLAY 0.617021 (-5502 2983);
PAINT PINK (-5502 2983);
FORCEPROP 2 LAST CDS_LIB mstr_standard
J 0
(-5500 2975);
PAINT MONO (-5500 2975);
DISPLAY INVISIBLE (-5500 2975);
FORCEPROP 1 LAST BODY_TYPE PLUMBING
J 0
(-5500 2925);
DISPLAY 1.595745 (-5500 2925);
PAINT GREEN (-5500 2925);
DISPLAY INVISIBLE (-5500 2925);
FORCEPROP 1 LAST HDL_TAP TRUE
J 0
(-5175 2850);
DISPLAY 1.595745 (-5175 2850);
PAINT GREEN (-5175 2850);
DISPLAY INVISIBLE (-5175 2850);
FORCEPROP 1 LAST PATH I51
J 0
(-5502 2975);
DISPLAY 0.872340 (-5502 2975);
PAINT GREEN (-5502 2975);
DISPLAY INVISIBLE (-5502 2975);
FORCEADD TAP..6
(-5500 3075);
FORCEPROP 3 LASTPIN (-5450 3075) SIG_NAME M_D_DQ<31>
J 0
(-5440 3085);
DISPLAY 0.659574 (-5440 3085);
PAINT MONO (-5440 3085);
DISPLAY INVISIBLE (-5440 3085);
FORCEPROP 1 LASTPIN (-5450 3075) BN 31
J 0
(-5502 3083);
DISPLAY 0.617021 (-5502 3083);
PAINT PINK (-5502 3083);
FORCEPROP 2 LAST CDS_LIB mstr_standard
J 0
(-5500 3075);
PAINT MONO (-5500 3075);
DISPLAY INVISIBLE (-5500 3075);
FORCEPROP 1 LAST BODY_TYPE PLUMBING
J 0
(-5500 3025);
DISPLAY 1.595745 (-5500 3025);
PAINT GREEN (-5500 3025);
DISPLAY INVISIBLE (-5500 3025);
FORCEPROP 1 LAST HDL_TAP TRUE
J 0
(-5175 2950);
DISPLAY 1.595745 (-5175 2950);
PAINT GREEN (-5175 2950);
DISPLAY INVISIBLE (-5175 2950);
FORCEPROP 1 LAST PATH I52
J 0
(-5502 3075);
DISPLAY 0.872340 (-5502 3075);
PAINT GREEN (-5502 3075);
DISPLAY INVISIBLE (-5502 3075);
FORCEADD TAP..6
(-5500 3025);
FORCEPROP 3 LASTPIN (-5450 3025) SIG_NAME M_D_DQ<30>
J 0
(-5440 3035);
DISPLAY 0.659574 (-5440 3035);
PAINT MONO (-5440 3035);
DISPLAY INVISIBLE (-5440 3035);
FORCEPROP 1 LASTPIN (-5450 3025) BN 30
J 0
(-5502 3033);
DISPLAY 0.617021 (-5502 3033);
PAINT PINK (-5502 3033);
FORCEPROP 2 LAST CDS_LIB mstr_standard
J 0
(-5500 3025);
PAINT MONO (-5500 3025);
DISPLAY INVISIBLE (-5500 3025);
FORCEPROP 1 LAST BODY_TYPE PLUMBING
J 0
(-5500 2975);
DISPLAY 1.595745 (-5500 2975);
PAINT GREEN (-5500 2975);
DISPLAY INVISIBLE (-5500 2975);
FORCEPROP 1 LAST HDL_TAP TRUE
J 0
(-5175 2900);
DISPLAY 1.595745 (-5175 2900);
PAINT GREEN (-5175 2900);
DISPLAY INVISIBLE (-5175 2900);
FORCEPROP 1 LAST PATH I53
J 0
(-5502 3025);
DISPLAY 0.872340 (-5502 3025);
PAINT GREEN (-5502 3025);
DISPLAY INVISIBLE (-5502 3025);
FORCEADD TAP..6
(-5500 3125);
FORCEPROP 3 LASTPIN (-5450 3125) SIG_NAME M_D_DQ<32>
J 0
(-5440 3135);
DISPLAY 0.659574 (-5440 3135);
PAINT MONO (-5440 3135);
DISPLAY INVISIBLE (-5440 3135);
FORCEPROP 1 LASTPIN (-5450 3125) BN 32
J 0
(-5502 3133);
DISPLAY 0.617021 (-5502 3133);
PAINT PINK (-5502 3133);
FORCEPROP 2 LAST CDS_LIB mstr_standard
J 0
(-5500 3125);
PAINT MONO (-5500 3125);
DISPLAY INVISIBLE (-5500 3125);
FORCEPROP 1 LAST BODY_TYPE PLUMBING
J 0
(-5500 3075);
DISPLAY 1.595745 (-5500 3075);
PAINT GREEN (-5500 3075);
DISPLAY INVISIBLE (-5500 3075);
FORCEPROP 1 LAST HDL_TAP TRUE
J 0
(-5175 3000);
DISPLAY 1.595745 (-5175 3000);
PAINT GREEN (-5175 3000);
DISPLAY INVISIBLE (-5175 3000);
FORCEPROP 1 LAST PATH I54
J 0
(-5502 3125);
DISPLAY 0.872340 (-5502 3125);
PAINT GREEN (-5502 3125);
DISPLAY INVISIBLE (-5502 3125);
FORCEADD TAP..6
(-5500 3175);
FORCEPROP 3 LASTPIN (-5450 3175) SIG_NAME M_D_DQ<33>
J 0
(-5440 3185);
DISPLAY 0.659574 (-5440 3185);
PAINT MONO (-5440 3185);
DISPLAY INVISIBLE (-5440 3185);
FORCEPROP 1 LASTPIN (-5450 3175) BN 33
J 0
(-5502 3183);
DISPLAY 0.617021 (-5502 3183);
PAINT PINK (-5502 3183);
FORCEPROP 2 LAST CDS_LIB mstr_standard
J 0
(-5500 3175);
PAINT MONO (-5500 3175);
DISPLAY INVISIBLE (-5500 3175);
FORCEPROP 1 LAST BODY_TYPE PLUMBING
J 0
(-5500 3125);
DISPLAY 1.595745 (-5500 3125);
PAINT GREEN (-5500 3125);
DISPLAY INVISIBLE (-5500 3125);
FORCEPROP 1 LAST HDL_TAP TRUE
J 0
(-5175 3050);
DISPLAY 1.595745 (-5175 3050);
PAINT GREEN (-5175 3050);
DISPLAY INVISIBLE (-5175 3050);
FORCEPROP 1 LAST PATH I55
J 0
(-5502 3175);
DISPLAY 0.872340 (-5502 3175);
PAINT GREEN (-5502 3175);
DISPLAY INVISIBLE (-5502 3175);
FORCEADD TAP..6
(-5500 3225);
FORCEPROP 3 LASTPIN (-5450 3225) SIG_NAME M_D_DQ<34>
J 0
(-5440 3235);
DISPLAY 0.659574 (-5440 3235);
PAINT MONO (-5440 3235);
DISPLAY INVISIBLE (-5440 3235);
FORCEPROP 1 LASTPIN (-5450 3225) BN 34
J 0
(-5502 3233);
DISPLAY 0.617021 (-5502 3233);
PAINT PINK (-5502 3233);
FORCEPROP 2 LAST CDS_LIB mstr_standard
J 0
(-5500 3225);
PAINT MONO (-5500 3225);
DISPLAY INVISIBLE (-5500 3225);
FORCEPROP 1 LAST BODY_TYPE PLUMBING
J 0
(-5500 3175);
DISPLAY 1.595745 (-5500 3175);
PAINT GREEN (-5500 3175);
DISPLAY INVISIBLE (-5500 3175);
FORCEPROP 1 LAST HDL_TAP TRUE
J 0
(-5175 3100);
DISPLAY 1.595745 (-5175 3100);
PAINT GREEN (-5175 3100);
DISPLAY INVISIBLE (-5175 3100);
FORCEPROP 1 LAST PATH I56
J 0
(-5502 3225);
DISPLAY 0.872340 (-5502 3225);
PAINT GREEN (-5502 3225);
DISPLAY INVISIBLE (-5502 3225);
FORCEADD TAP..6
(-5500 3325);
FORCEPROP 3 LASTPIN (-5450 3325) SIG_NAME M_D_DQ<36>
J 0
(-5440 3335);
DISPLAY 0.659574 (-5440 3335);
PAINT MONO (-5440 3335);
DISPLAY INVISIBLE (-5440 3335);
FORCEPROP 1 LASTPIN (-5450 3325) BN 36
J 0
(-5502 3333);
DISPLAY 0.617021 (-5502 3333);
PAINT PINK (-5502 3333);
FORCEPROP 2 LAST CDS_LIB mstr_standard
J 0
(-5500 3325);
PAINT MONO (-5500 3325);
DISPLAY INVISIBLE (-5500 3325);
FORCEPROP 1 LAST BODY_TYPE PLUMBING
J 0
(-5500 3275);
DISPLAY 1.595745 (-5500 3275);
PAINT GREEN (-5500 3275);
DISPLAY INVISIBLE (-5500 3275);
FORCEPROP 1 LAST HDL_TAP TRUE
J 0
(-5175 3200);
DISPLAY 1.595745 (-5175 3200);
PAINT GREEN (-5175 3200);
DISPLAY INVISIBLE (-5175 3200);
FORCEPROP 1 LAST PATH I57
J 0
(-5502 3325);
DISPLAY 0.872340 (-5502 3325);
PAINT GREEN (-5502 3325);
DISPLAY INVISIBLE (-5502 3325);
FORCEADD TAP..6
(-5500 3275);
FORCEPROP 3 LASTPIN (-5450 3275) SIG_NAME M_D_DQ<35>
J 0
(-5440 3285);
DISPLAY 0.659574 (-5440 3285);
PAINT MONO (-5440 3285);
DISPLAY INVISIBLE (-5440 3285);
FORCEPROP 1 LASTPIN (-5450 3275) BN 35
J 0
(-5502 3283);
DISPLAY 0.617021 (-5502 3283);
PAINT PINK (-5502 3283);
FORCEPROP 2 LAST CDS_LIB mstr_standard
J 0
(-5500 3275);
PAINT MONO (-5500 3275);
DISPLAY INVISIBLE (-5500 3275);
FORCEPROP 1 LAST BODY_TYPE PLUMBING
J 0
(-5500 3225);
DISPLAY 1.595745 (-5500 3225);
PAINT GREEN (-5500 3225);
DISPLAY INVISIBLE (-5500 3225);
FORCEPROP 1 LAST HDL_TAP TRUE
J 0
(-5175 3150);
DISPLAY 1.595745 (-5175 3150);
PAINT GREEN (-5175 3150);
DISPLAY INVISIBLE (-5175 3150);
FORCEPROP 1 LAST PATH I58
J 0
(-5502 3275);
DISPLAY 0.872340 (-5502 3275);
PAINT GREEN (-5502 3275);
DISPLAY INVISIBLE (-5502 3275);
FORCEADD TAP..6
(-5500 3375);
FORCEPROP 3 LASTPIN (-5450 3375) SIG_NAME M_D_DQ<37>
J 0
(-5440 3385);
DISPLAY 0.659574 (-5440 3385);
PAINT MONO (-5440 3385);
DISPLAY INVISIBLE (-5440 3385);
FORCEPROP 1 LASTPIN (-5450 3375) BN 37
J 0
(-5502 3383);
DISPLAY 0.617021 (-5502 3383);
PAINT PINK (-5502 3383);
FORCEPROP 2 LAST CDS_LIB mstr_standard
J 0
(-5500 3375);
PAINT MONO (-5500 3375);
DISPLAY INVISIBLE (-5500 3375);
FORCEPROP 1 LAST BODY_TYPE PLUMBING
J 0
(-5500 3325);
DISPLAY 1.595745 (-5500 3325);
PAINT GREEN (-5500 3325);
DISPLAY INVISIBLE (-5500 3325);
FORCEPROP 1 LAST HDL_TAP TRUE
J 0
(-5175 3250);
DISPLAY 1.595745 (-5175 3250);
PAINT GREEN (-5175 3250);
DISPLAY INVISIBLE (-5175 3250);
FORCEPROP 1 LAST PATH I59
J 0
(-5502 3375);
DISPLAY 0.872340 (-5502 3375);
PAINT GREEN (-5502 3375);
DISPLAY INVISIBLE (-5502 3375);
FORCEADD TAP..6
(-5500 675);
FORCEPROP 3 LASTPIN (-5450 675) SIG_NAME M_D_CLK_DN<1>
J 0
(-5440 685);
DISPLAY 0.659574 (-5440 685);
PAINT MONO (-5440 685);
DISPLAY INVISIBLE (-5440 685);
FORCEPROP 1 LASTPIN (-5450 675) BN 1
J 0
(-5502 683);
DISPLAY 0.617021 (-5502 683);
PAINT PINK (-5502 683);
FORCEPROP 2 LAST CDS_LIB mstr_standard
J 0
(-5500 675);
PAINT MONO (-5500 675);
DISPLAY INVISIBLE (-5500 675);
FORCEPROP 1 LAST BODY_TYPE PLUMBING
J 0
(-5500 625);
DISPLAY 1.595745 (-5500 625);
PAINT GREEN (-5500 625);
DISPLAY INVISIBLE (-5500 625);
FORCEPROP 1 LAST HDL_TAP TRUE
J 0
(-5175 550);
DISPLAY 1.595745 (-5175 550);
PAINT GREEN (-5175 550);
DISPLAY INVISIBLE (-5175 550);
FORCEPROP 1 LAST PATH I6
J 0
(-5502 675);
DISPLAY 0.872340 (-5502 675);
PAINT GREEN (-5502 675);
DISPLAY INVISIBLE (-5502 675);
FORCEADD TAP..6
(-5500 3425);
FORCEPROP 3 LASTPIN (-5450 3425) SIG_NAME M_D_DQ<38>
J 0
(-5440 3435);
DISPLAY 0.659574 (-5440 3435);
PAINT MONO (-5440 3435);
DISPLAY INVISIBLE (-5440 3435);
FORCEPROP 1 LASTPIN (-5450 3425) BN 38
J 0
(-5502 3433);
DISPLAY 0.617021 (-5502 3433);
PAINT PINK (-5502 3433);
FORCEPROP 2 LAST CDS_LIB mstr_standard
J 0
(-5500 3425);
PAINT MONO (-5500 3425);
DISPLAY INVISIBLE (-5500 3425);
FORCEPROP 1 LAST BODY_TYPE PLUMBING
J 0
(-5500 3375);
DISPLAY 1.595745 (-5500 3375);
PAINT GREEN (-5500 3375);
DISPLAY INVISIBLE (-5500 3375);
FORCEPROP 1 LAST HDL_TAP TRUE
J 0
(-5175 3300);
DISPLAY 1.595745 (-5175 3300);
PAINT GREEN (-5175 3300);
DISPLAY INVISIBLE (-5175 3300);
FORCEPROP 1 LAST PATH I60
J 0
(-5502 3425);
DISPLAY 0.872340 (-5502 3425);
PAINT GREEN (-5502 3425);
DISPLAY INVISIBLE (-5502 3425);
FORCEADD TAP..6
(-5500 3475);
FORCEPROP 3 LASTPIN (-5450 3475) SIG_NAME M_D_DQ<39>
J 0
(-5440 3485);
DISPLAY 0.659574 (-5440 3485);
PAINT MONO (-5440 3485);
DISPLAY INVISIBLE (-5440 3485);
FORCEPROP 1 LASTPIN (-5450 3475) BN 39
J 0
(-5502 3483);
DISPLAY 0.617021 (-5502 3483);
PAINT PINK (-5502 3483);
FORCEPROP 2 LAST CDS_LIB mstr_standard
J 0
(-5500 3475);
PAINT MONO (-5500 3475);
DISPLAY INVISIBLE (-5500 3475);
FORCEPROP 1 LAST BODY_TYPE PLUMBING
J 0
(-5500 3425);
DISPLAY 1.595745 (-5500 3425);
PAINT GREEN (-5500 3425);
DISPLAY INVISIBLE (-5500 3425);
FORCEPROP 1 LAST HDL_TAP TRUE
J 0
(-5175 3350);
DISPLAY 1.595745 (-5175 3350);
PAINT GREEN (-5175 3350);
DISPLAY INVISIBLE (-5175 3350);
FORCEPROP 1 LAST PATH I61
J 0
(-5502 3475);
DISPLAY 0.872340 (-5502 3475);
PAINT GREEN (-5502 3475);
DISPLAY INVISIBLE (-5502 3475);
FORCEADD TAP..6
(-5500 3525);
FORCEPROP 3 LASTPIN (-5450 3525) SIG_NAME M_D_DQ<40>
J 0
(-5440 3535);
DISPLAY 0.659574 (-5440 3535);
PAINT MONO (-5440 3535);
DISPLAY INVISIBLE (-5440 3535);
FORCEPROP 1 LASTPIN (-5450 3525) BN 40
J 0
(-5502 3533);
DISPLAY 0.617021 (-5502 3533);
PAINT PINK (-5502 3533);
FORCEPROP 2 LAST CDS_LIB mstr_standard
J 0
(-5500 3525);
PAINT MONO (-5500 3525);
DISPLAY INVISIBLE (-5500 3525);
FORCEPROP 1 LAST BODY_TYPE PLUMBING
J 0
(-5500 3475);
DISPLAY 1.595745 (-5500 3475);
PAINT GREEN (-5500 3475);
DISPLAY INVISIBLE (-5500 3475);
FORCEPROP 1 LAST HDL_TAP TRUE
J 0
(-5175 3400);
DISPLAY 1.595745 (-5175 3400);
PAINT GREEN (-5175 3400);
DISPLAY INVISIBLE (-5175 3400);
FORCEPROP 1 LAST PATH I62
J 0
(-5502 3525);
DISPLAY 0.872340 (-5502 3525);
PAINT GREEN (-5502 3525);
DISPLAY INVISIBLE (-5502 3525);
FORCEADD TAP..6
(-5500 3575);
FORCEPROP 3 LASTPIN (-5450 3575) SIG_NAME M_D_DQ<41>
J 0
(-5440 3585);
DISPLAY 0.659574 (-5440 3585);
PAINT MONO (-5440 3585);
DISPLAY INVISIBLE (-5440 3585);
FORCEPROP 1 LASTPIN (-5450 3575) BN 41
J 0
(-5502 3583);
DISPLAY 0.617021 (-5502 3583);
PAINT PINK (-5502 3583);
FORCEPROP 2 LAST CDS_LIB mstr_standard
J 0
(-5500 3575);
PAINT MONO (-5500 3575);
DISPLAY INVISIBLE (-5500 3575);
FORCEPROP 1 LAST BODY_TYPE PLUMBING
J 0
(-5500 3525);
DISPLAY 1.595745 (-5500 3525);
PAINT GREEN (-5500 3525);
DISPLAY INVISIBLE (-5500 3525);
FORCEPROP 1 LAST HDL_TAP TRUE
J 0
(-5175 3450);
DISPLAY 1.595745 (-5175 3450);
PAINT GREEN (-5175 3450);
DISPLAY INVISIBLE (-5175 3450);
FORCEPROP 1 LAST PATH I63
J 0
(-5502 3575);
DISPLAY 0.872340 (-5502 3575);
PAINT GREEN (-5502 3575);
DISPLAY INVISIBLE (-5502 3575);
FORCEADD TAP..6
(-5500 3625);
FORCEPROP 3 LASTPIN (-5450 3625) SIG_NAME M_D_DQ<42>
J 0
(-5440 3635);
DISPLAY 0.659574 (-5440 3635);
PAINT MONO (-5440 3635);
DISPLAY INVISIBLE (-5440 3635);
FORCEPROP 1 LASTPIN (-5450 3625) BN 42
J 0
(-5502 3633);
DISPLAY 0.617021 (-5502 3633);
PAINT PINK (-5502 3633);
FORCEPROP 2 LAST CDS_LIB mstr_standard
J 0
(-5500 3625);
PAINT MONO (-5500 3625);
DISPLAY INVISIBLE (-5500 3625);
FORCEPROP 1 LAST BODY_TYPE PLUMBING
J 0
(-5500 3575);
DISPLAY 1.595745 (-5500 3575);
PAINT GREEN (-5500 3575);
DISPLAY INVISIBLE (-5500 3575);
FORCEPROP 1 LAST HDL_TAP TRUE
J 0
(-5175 3500);
DISPLAY 1.595745 (-5175 3500);
PAINT GREEN (-5175 3500);
DISPLAY INVISIBLE (-5175 3500);
FORCEPROP 1 LAST PATH I64
J 0
(-5502 3625);
DISPLAY 0.872340 (-5502 3625);
PAINT GREEN (-5502 3625);
DISPLAY INVISIBLE (-5502 3625);
FORCEADD TAP..6
(-5500 3675);
FORCEPROP 3 LASTPIN (-5450 3675) SIG_NAME M_D_DQ<43>
J 0
(-5440 3685);
DISPLAY 0.659574 (-5440 3685);
PAINT MONO (-5440 3685);
DISPLAY INVISIBLE (-5440 3685);
FORCEPROP 1 LASTPIN (-5450 3675) BN 43
J 0
(-5502 3683);
DISPLAY 0.617021 (-5502 3683);
PAINT PINK (-5502 3683);
FORCEPROP 2 LAST CDS_LIB mstr_standard
J 0
(-5500 3675);
PAINT MONO (-5500 3675);
DISPLAY INVISIBLE (-5500 3675);
FORCEPROP 1 LAST BODY_TYPE PLUMBING
J 0
(-5500 3625);
DISPLAY 1.595745 (-5500 3625);
PAINT GREEN (-5500 3625);
DISPLAY INVISIBLE (-5500 3625);
FORCEPROP 1 LAST HDL_TAP TRUE
J 0
(-5175 3550);
DISPLAY 1.595745 (-5175 3550);
PAINT GREEN (-5175 3550);
DISPLAY INVISIBLE (-5175 3550);
FORCEPROP 1 LAST PATH I65
J 0
(-5502 3675);
DISPLAY 0.872340 (-5502 3675);
PAINT GREEN (-5502 3675);
DISPLAY INVISIBLE (-5502 3675);
FORCEADD TAP..6
(-5500 3725);
FORCEPROP 3 LASTPIN (-5450 3725) SIG_NAME M_D_DQ<44>
J 0
(-5440 3735);
DISPLAY 0.659574 (-5440 3735);
PAINT MONO (-5440 3735);
DISPLAY INVISIBLE (-5440 3735);
FORCEPROP 1 LASTPIN (-5450 3725) BN 44
J 0
(-5502 3733);
DISPLAY 0.617021 (-5502 3733);
PAINT PINK (-5502 3733);
FORCEPROP 2 LAST CDS_LIB mstr_standard
J 0
(-5500 3725);
PAINT MONO (-5500 3725);
DISPLAY INVISIBLE (-5500 3725);
FORCEPROP 1 LAST BODY_TYPE PLUMBING
J 0
(-5500 3675);
DISPLAY 1.595745 (-5500 3675);
PAINT GREEN (-5500 3675);
DISPLAY INVISIBLE (-5500 3675);
FORCEPROP 1 LAST HDL_TAP TRUE
J 0
(-5175 3600);
DISPLAY 1.595745 (-5175 3600);
PAINT GREEN (-5175 3600);
DISPLAY INVISIBLE (-5175 3600);
FORCEPROP 1 LAST PATH I66
J 0
(-5502 3725);
DISPLAY 0.872340 (-5502 3725);
PAINT GREEN (-5502 3725);
DISPLAY INVISIBLE (-5502 3725);
FORCEADD TAP..6
(-5500 3775);
FORCEPROP 3 LASTPIN (-5450 3775) SIG_NAME M_D_DQ<45>
J 0
(-5440 3785);
DISPLAY 0.659574 (-5440 3785);
PAINT MONO (-5440 3785);
DISPLAY INVISIBLE (-5440 3785);
FORCEPROP 1 LASTPIN (-5450 3775) BN 45
J 0
(-5502 3783);
DISPLAY 0.617021 (-5502 3783);
PAINT PINK (-5502 3783);
FORCEPROP 2 LAST CDS_LIB mstr_standard
J 0
(-5500 3775);
PAINT MONO (-5500 3775);
DISPLAY INVISIBLE (-5500 3775);
FORCEPROP 1 LAST BODY_TYPE PLUMBING
J 0
(-5500 3725);
DISPLAY 1.595745 (-5500 3725);
PAINT GREEN (-5500 3725);
DISPLAY INVISIBLE (-5500 3725);
FORCEPROP 1 LAST HDL_TAP TRUE
J 0
(-5175 3650);
DISPLAY 1.595745 (-5175 3650);
PAINT GREEN (-5175 3650);
DISPLAY INVISIBLE (-5175 3650);
FORCEPROP 1 LAST PATH I67
J 0
(-5502 3775);
DISPLAY 0.872340 (-5502 3775);
PAINT GREEN (-5502 3775);
DISPLAY INVISIBLE (-5502 3775);
FORCEADD TAP..6
(-5500 3825);
FORCEPROP 3 LASTPIN (-5450 3825) SIG_NAME M_D_DQ<46>
J 0
(-5440 3835);
DISPLAY 0.659574 (-5440 3835);
PAINT MONO (-5440 3835);
DISPLAY INVISIBLE (-5440 3835);
FORCEPROP 1 LASTPIN (-5450 3825) BN 46
J 0
(-5502 3833);
DISPLAY 0.617021 (-5502 3833);
PAINT PINK (-5502 3833);
FORCEPROP 2 LAST CDS_LIB mstr_standard
J 0
(-5500 3825);
PAINT MONO (-5500 3825);
DISPLAY INVISIBLE (-5500 3825);
FORCEPROP 1 LAST BODY_TYPE PLUMBING
J 0
(-5500 3775);
DISPLAY 1.595745 (-5500 3775);
PAINT GREEN (-5500 3775);
DISPLAY INVISIBLE (-5500 3775);
FORCEPROP 1 LAST HDL_TAP TRUE
J 0
(-5175 3700);
DISPLAY 1.595745 (-5175 3700);
PAINT GREEN (-5175 3700);
DISPLAY INVISIBLE (-5175 3700);
FORCEPROP 1 LAST PATH I68
J 0
(-5502 3825);
DISPLAY 0.872340 (-5502 3825);
PAINT GREEN (-5502 3825);
DISPLAY INVISIBLE (-5502 3825);
FORCEADD TAP..6
(-5500 3875);
FORCEPROP 3 LASTPIN (-5450 3875) SIG_NAME M_D_DQ<47>
J 0
(-5440 3885);
DISPLAY 0.659574 (-5440 3885);
PAINT MONO (-5440 3885);
DISPLAY INVISIBLE (-5440 3885);
FORCEPROP 1 LASTPIN (-5450 3875) BN 47
J 0
(-5502 3883);
DISPLAY 0.617021 (-5502 3883);
PAINT PINK (-5502 3883);
FORCEPROP 2 LAST CDS_LIB mstr_standard
J 0
(-5500 3875);
PAINT MONO (-5500 3875);
DISPLAY INVISIBLE (-5500 3875);
FORCEPROP 1 LAST BODY_TYPE PLUMBING
J 0
(-5500 3825);
DISPLAY 1.595745 (-5500 3825);
PAINT GREEN (-5500 3825);
DISPLAY INVISIBLE (-5500 3825);
FORCEPROP 1 LAST HDL_TAP TRUE
J 0
(-5175 3750);
DISPLAY 1.595745 (-5175 3750);
PAINT GREEN (-5175 3750);
DISPLAY INVISIBLE (-5175 3750);
FORCEPROP 1 LAST PATH I69
J 0
(-5502 3875);
DISPLAY 0.872340 (-5502 3875);
PAINT GREEN (-5502 3875);
DISPLAY INVISIBLE (-5502 3875);
FORCEADD TAP..6
(-5500 775);
FORCEPROP 3 LASTPIN (-5450 775) SIG_NAME M_D_CLK_DN<3>
J 0
(-5440 785);
DISPLAY 0.659574 (-5440 785);
PAINT MONO (-5440 785);
DISPLAY INVISIBLE (-5440 785);
FORCEPROP 1 LASTPIN (-5450 775) BN 3
J 0
(-5502 783);
DISPLAY 0.617021 (-5502 783);
PAINT PINK (-5502 783);
FORCEPROP 2 LAST CDS_LIB mstr_standard
J 0
(-5500 775);
PAINT MONO (-5500 775);
DISPLAY INVISIBLE (-5500 775);
FORCEPROP 1 LAST BODY_TYPE PLUMBING
J 0
(-5500 725);
DISPLAY 1.595745 (-5500 725);
PAINT GREEN (-5500 725);
DISPLAY INVISIBLE (-5500 725);
FORCEPROP 1 LAST HDL_TAP TRUE
J 0
(-5175 650);
DISPLAY 1.595745 (-5175 650);
PAINT GREEN (-5175 650);
DISPLAY INVISIBLE (-5175 650);
FORCEPROP 1 LAST PATH I7
J 0
(-5502 775);
DISPLAY 0.872340 (-5502 775);
PAINT GREEN (-5502 775);
DISPLAY INVISIBLE (-5502 775);
FORCEADD TAP..6
(-5500 3925);
FORCEPROP 3 LASTPIN (-5450 3925) SIG_NAME M_D_DQ<48>
J 0
(-5440 3935);
DISPLAY 0.659574 (-5440 3935);
PAINT MONO (-5440 3935);
DISPLAY INVISIBLE (-5440 3935);
FORCEPROP 1 LASTPIN (-5450 3925) BN 48
J 0
(-5502 3933);
DISPLAY 0.617021 (-5502 3933);
PAINT PINK (-5502 3933);
FORCEPROP 2 LAST CDS_LIB mstr_standard
J 0
(-5500 3925);
PAINT MONO (-5500 3925);
DISPLAY INVISIBLE (-5500 3925);
FORCEPROP 1 LAST BODY_TYPE PLUMBING
J 0
(-5500 3875);
DISPLAY 1.595745 (-5500 3875);
PAINT GREEN (-5500 3875);
DISPLAY INVISIBLE (-5500 3875);
FORCEPROP 1 LAST HDL_TAP TRUE
J 0
(-5175 3800);
DISPLAY 1.595745 (-5175 3800);
PAINT GREEN (-5175 3800);
DISPLAY INVISIBLE (-5175 3800);
FORCEPROP 1 LAST PATH I70
J 0
(-5502 3925);
DISPLAY 0.872340 (-5502 3925);
PAINT GREEN (-5502 3925);
DISPLAY INVISIBLE (-5502 3925);
FORCEADD TAP..6
(-5500 3975);
FORCEPROP 3 LASTPIN (-5450 3975) SIG_NAME M_D_DQ<49>
J 0
(-5440 3985);
DISPLAY 0.659574 (-5440 3985);
PAINT MONO (-5440 3985);
DISPLAY INVISIBLE (-5440 3985);
FORCEPROP 1 LASTPIN (-5450 3975) BN 49
J 0
(-5502 3983);
DISPLAY 0.617021 (-5502 3983);
PAINT PINK (-5502 3983);
FORCEPROP 2 LAST CDS_LIB mstr_standard
J 0
(-5500 3975);
PAINT MONO (-5500 3975);
DISPLAY INVISIBLE (-5500 3975);
FORCEPROP 1 LAST BODY_TYPE PLUMBING
J 0
(-5500 3925);
DISPLAY 1.595745 (-5500 3925);
PAINT GREEN (-5500 3925);
DISPLAY INVISIBLE (-5500 3925);
FORCEPROP 1 LAST HDL_TAP TRUE
J 0
(-5175 3850);
DISPLAY 1.595745 (-5175 3850);
PAINT GREEN (-5175 3850);
DISPLAY INVISIBLE (-5175 3850);
FORCEPROP 1 LAST PATH I71
J 0
(-5502 3975);
DISPLAY 0.872340 (-5502 3975);
PAINT GREEN (-5502 3975);
DISPLAY INVISIBLE (-5502 3975);
FORCEADD OFFPAGE..6
(-6350 4800);
FORCEPROP 2 LAST $XR0 49 
J 0
(-6629 4800);
DISPLAY 0.638298 (-6629 4800);
PAINT MONO (-6629 4800);
FORCEPROP 2 LAST $XR1 50 
J 0
(-6719 4800);
DISPLAY 0.638298 (-6719 4800);
PAINT MONO (-6719 4800);
FORCEPROP 2 LAST CDS_LIB mstr_standard
J 0
(-6350 4800);
PAINT MONO (-6350 4800);
DISPLAY INVISIBLE (-6350 4800);
FORCEPROP 1 LAST OFFPAGE TRUE
J 0
(-6025 4675);
DISPLAY 1.170213 (-6025 4675);
PAINT GREEN (-6025 4675);
DISPLAY INVISIBLE (-6025 4675);
FORCEPROP 1 LAST COMMENT_BODY TRUE
J 0
(-6250 4725);
DISPLAY 1.170213 (-6250 4725);
PAINT GREEN (-6250 4725);
DISPLAY INVISIBLE (-6250 4725);
FORCEPROP 2 LAST PATH I72
J 0
(-6300 4875);
DISPLAY 1.021277 (-6300 4875);
PAINT ORANGE (-6300 4875);
DISPLAY INVISIBLE (-6300 4875);
FORCEADD TAP..6
(-5500 4025);
FORCEPROP 3 LASTPIN (-5450 4025) SIG_NAME M_D_DQ<50>
J 0
(-5440 4035);
DISPLAY 0.659574 (-5440 4035);
PAINT MONO (-5440 4035);
DISPLAY INVISIBLE (-5440 4035);
FORCEPROP 1 LASTPIN (-5450 4025) BN 50
J 0
(-5502 4033);
DISPLAY 0.617021 (-5502 4033);
PAINT PINK (-5502 4033);
FORCEPROP 2 LAST CDS_LIB mstr_standard
J 0
(-5500 4025);
PAINT MONO (-5500 4025);
DISPLAY INVISIBLE (-5500 4025);
FORCEPROP 1 LAST BODY_TYPE PLUMBING
J 0
(-5500 3975);
DISPLAY 1.595745 (-5500 3975);
PAINT GREEN (-5500 3975);
DISPLAY INVISIBLE (-5500 3975);
FORCEPROP 1 LAST HDL_TAP TRUE
J 0
(-5175 3900);
DISPLAY 1.595745 (-5175 3900);
PAINT GREEN (-5175 3900);
DISPLAY INVISIBLE (-5175 3900);
FORCEPROP 1 LAST PATH I73
J 0
(-5502 4025);
DISPLAY 0.872340 (-5502 4025);
PAINT GREEN (-5502 4025);
DISPLAY INVISIBLE (-5502 4025);
FORCEADD TAP..6
(-5500 4075);
FORCEPROP 3 LASTPIN (-5450 4075) SIG_NAME M_D_DQ<51>
J 0
(-5440 4085);
DISPLAY 0.659574 (-5440 4085);
PAINT MONO (-5440 4085);
DISPLAY INVISIBLE (-5440 4085);
FORCEPROP 1 LASTPIN (-5450 4075) BN 51
J 0
(-5502 4083);
DISPLAY 0.617021 (-5502 4083);
PAINT PINK (-5502 4083);
FORCEPROP 2 LAST CDS_LIB mstr_standard
J 0
(-5500 4075);
PAINT MONO (-5500 4075);
DISPLAY INVISIBLE (-5500 4075);
FORCEPROP 1 LAST BODY_TYPE PLUMBING
J 0
(-5500 4025);
DISPLAY 1.595745 (-5500 4025);
PAINT GREEN (-5500 4025);
DISPLAY INVISIBLE (-5500 4025);
FORCEPROP 1 LAST HDL_TAP TRUE
J 0
(-5175 3950);
DISPLAY 1.595745 (-5175 3950);
PAINT GREEN (-5175 3950);
DISPLAY INVISIBLE (-5175 3950);
FORCEPROP 1 LAST PATH I74
J 0
(-5502 4075);
DISPLAY 0.872340 (-5502 4075);
PAINT GREEN (-5502 4075);
DISPLAY INVISIBLE (-5502 4075);
FORCEADD TAP..6
(-5500 4125);
FORCEPROP 3 LASTPIN (-5450 4125) SIG_NAME M_D_DQ<52>
J 0
(-5440 4135);
DISPLAY 0.659574 (-5440 4135);
PAINT MONO (-5440 4135);
DISPLAY INVISIBLE (-5440 4135);
FORCEPROP 1 LASTPIN (-5450 4125) BN 52
J 0
(-5502 4133);
DISPLAY 0.617021 (-5502 4133);
PAINT PINK (-5502 4133);
FORCEPROP 2 LAST CDS_LIB mstr_standard
J 0
(-5500 4125);
PAINT MONO (-5500 4125);
DISPLAY INVISIBLE (-5500 4125);
FORCEPROP 1 LAST BODY_TYPE PLUMBING
J 0
(-5500 4075);
DISPLAY 1.595745 (-5500 4075);
PAINT GREEN (-5500 4075);
DISPLAY INVISIBLE (-5500 4075);
FORCEPROP 1 LAST HDL_TAP TRUE
J 0
(-5175 4000);
DISPLAY 1.595745 (-5175 4000);
PAINT GREEN (-5175 4000);
DISPLAY INVISIBLE (-5175 4000);
FORCEPROP 1 LAST PATH I75
J 0
(-5502 4125);
DISPLAY 0.872340 (-5502 4125);
PAINT GREEN (-5502 4125);
DISPLAY INVISIBLE (-5502 4125);
FORCEADD TAP..6
(-5500 4175);
FORCEPROP 3 LASTPIN (-5450 4175) SIG_NAME M_D_DQ<53>
J 0
(-5440 4185);
DISPLAY 0.659574 (-5440 4185);
PAINT MONO (-5440 4185);
DISPLAY INVISIBLE (-5440 4185);
FORCEPROP 1 LASTPIN (-5450 4175) BN 53
J 0
(-5502 4183);
DISPLAY 0.617021 (-5502 4183);
PAINT PINK (-5502 4183);
FORCEPROP 2 LAST CDS_LIB mstr_standard
J 0
(-5500 4175);
PAINT MONO (-5500 4175);
DISPLAY INVISIBLE (-5500 4175);
FORCEPROP 1 LAST BODY_TYPE PLUMBING
J 0
(-5500 4125);
DISPLAY 1.595745 (-5500 4125);
PAINT GREEN (-5500 4125);
DISPLAY INVISIBLE (-5500 4125);
FORCEPROP 1 LAST HDL_TAP TRUE
J 0
(-5175 4050);
DISPLAY 1.595745 (-5175 4050);
PAINT GREEN (-5175 4050);
DISPLAY INVISIBLE (-5175 4050);
FORCEPROP 1 LAST PATH I76
J 0
(-5502 4175);
DISPLAY 0.872340 (-5502 4175);
PAINT GREEN (-5502 4175);
DISPLAY INVISIBLE (-5502 4175);
FORCEADD TAP..6
(-5500 4225);
FORCEPROP 3 LASTPIN (-5450 4225) SIG_NAME M_D_DQ<54>
J 0
(-5440 4235);
DISPLAY 0.659574 (-5440 4235);
PAINT MONO (-5440 4235);
DISPLAY INVISIBLE (-5440 4235);
FORCEPROP 1 LASTPIN (-5450 4225) BN 54
J 0
(-5502 4233);
DISPLAY 0.617021 (-5502 4233);
PAINT PINK (-5502 4233);
FORCEPROP 2 LAST CDS_LIB mstr_standard
J 0
(-5500 4225);
PAINT MONO (-5500 4225);
DISPLAY INVISIBLE (-5500 4225);
FORCEPROP 1 LAST BODY_TYPE PLUMBING
J 0
(-5500 4175);
DISPLAY 1.595745 (-5500 4175);
PAINT GREEN (-5500 4175);
DISPLAY INVISIBLE (-5500 4175);
FORCEPROP 1 LAST HDL_TAP TRUE
J 0
(-5175 4100);
DISPLAY 1.595745 (-5175 4100);
PAINT GREEN (-5175 4100);
DISPLAY INVISIBLE (-5175 4100);
FORCEPROP 1 LAST PATH I77
J 0
(-5502 4225);
DISPLAY 0.872340 (-5502 4225);
PAINT GREEN (-5502 4225);
DISPLAY INVISIBLE (-5502 4225);
FORCEADD TAP..6
(-5500 4275);
FORCEPROP 3 LASTPIN (-5450 4275) SIG_NAME M_D_DQ<55>
J 0
(-5440 4285);
DISPLAY 0.659574 (-5440 4285);
PAINT MONO (-5440 4285);
DISPLAY INVISIBLE (-5440 4285);
FORCEPROP 1 LASTPIN (-5450 4275) BN 55
J 0
(-5502 4283);
DISPLAY 0.617021 (-5502 4283);
PAINT PINK (-5502 4283);
FORCEPROP 2 LAST CDS_LIB mstr_standard
J 0
(-5500 4275);
PAINT MONO (-5500 4275);
DISPLAY INVISIBLE (-5500 4275);
FORCEPROP 1 LAST BODY_TYPE PLUMBING
J 0
(-5500 4225);
DISPLAY 1.595745 (-5500 4225);
PAINT GREEN (-5500 4225);
DISPLAY INVISIBLE (-5500 4225);
FORCEPROP 1 LAST HDL_TAP TRUE
J 0
(-5175 4150);
DISPLAY 1.595745 (-5175 4150);
PAINT GREEN (-5175 4150);
DISPLAY INVISIBLE (-5175 4150);
FORCEPROP 1 LAST PATH I78
J 0
(-5502 4275);
DISPLAY 0.872340 (-5502 4275);
PAINT GREEN (-5502 4275);
DISPLAY INVISIBLE (-5502 4275);
FORCEADD TAP..6
(-5500 4325);
FORCEPROP 3 LASTPIN (-5450 4325) SIG_NAME M_D_DQ<56>
J 0
(-5440 4335);
DISPLAY 0.659574 (-5440 4335);
PAINT MONO (-5440 4335);
DISPLAY INVISIBLE (-5440 4335);
FORCEPROP 1 LASTPIN (-5450 4325) BN 56
J 0
(-5502 4333);
DISPLAY 0.617021 (-5502 4333);
PAINT PINK (-5502 4333);
FORCEPROP 2 LAST CDS_LIB mstr_standard
J 0
(-5500 4325);
PAINT MONO (-5500 4325);
DISPLAY INVISIBLE (-5500 4325);
FORCEPROP 1 LAST BODY_TYPE PLUMBING
J 0
(-5500 4275);
DISPLAY 1.595745 (-5500 4275);
PAINT GREEN (-5500 4275);
DISPLAY INVISIBLE (-5500 4275);
FORCEPROP 1 LAST HDL_TAP TRUE
J 0
(-5175 4200);
DISPLAY 1.595745 (-5175 4200);
PAINT GREEN (-5175 4200);
DISPLAY INVISIBLE (-5175 4200);
FORCEPROP 1 LAST PATH I79
J 0
(-5502 4325);
DISPLAY 0.872340 (-5502 4325);
PAINT GREEN (-5502 4325);
DISPLAY INVISIBLE (-5502 4325);
FORCEADD TAP..6
(-5500 725);
FORCEPROP 3 LASTPIN (-5450 725) SIG_NAME M_D_CLK_DN<2>
J 0
(-5440 735);
DISPLAY 0.659574 (-5440 735);
PAINT MONO (-5440 735);
DISPLAY INVISIBLE (-5440 735);
FORCEPROP 1 LASTPIN (-5450 725) BN 2
J 0
(-5502 733);
DISPLAY 0.617021 (-5502 733);
PAINT PINK (-5502 733);
FORCEPROP 2 LAST CDS_LIB mstr_standard
J 0
(-5500 725);
PAINT MONO (-5500 725);
DISPLAY INVISIBLE (-5500 725);
FORCEPROP 1 LAST BODY_TYPE PLUMBING
J 0
(-5500 675);
DISPLAY 1.595745 (-5500 675);
PAINT GREEN (-5500 675);
DISPLAY INVISIBLE (-5500 675);
FORCEPROP 1 LAST HDL_TAP TRUE
J 0
(-5175 600);
DISPLAY 1.595745 (-5175 600);
PAINT GREEN (-5175 600);
DISPLAY INVISIBLE (-5175 600);
FORCEPROP 1 LAST PATH I8
J 0
(-5502 725);
DISPLAY 0.872340 (-5502 725);
PAINT GREEN (-5502 725);
DISPLAY INVISIBLE (-5502 725);
FORCEADD TAP..6
(-5500 4375);
FORCEPROP 3 LASTPIN (-5450 4375) SIG_NAME M_D_DQ<57>
J 0
(-5440 4385);
DISPLAY 0.659574 (-5440 4385);
PAINT MONO (-5440 4385);
DISPLAY INVISIBLE (-5440 4385);
FORCEPROP 1 LASTPIN (-5450 4375) BN 57
J 0
(-5502 4383);
DISPLAY 0.617021 (-5502 4383);
PAINT PINK (-5502 4383);
FORCEPROP 2 LAST CDS_LIB mstr_standard
J 0
(-5500 4375);
PAINT MONO (-5500 4375);
DISPLAY INVISIBLE (-5500 4375);
FORCEPROP 1 LAST BODY_TYPE PLUMBING
J 0
(-5500 4325);
DISPLAY 1.595745 (-5500 4325);
PAINT GREEN (-5500 4325);
DISPLAY INVISIBLE (-5500 4325);
FORCEPROP 1 LAST HDL_TAP TRUE
J 0
(-5175 4250);
DISPLAY 1.595745 (-5175 4250);
PAINT GREEN (-5175 4250);
DISPLAY INVISIBLE (-5175 4250);
FORCEPROP 1 LAST PATH I80
J 0
(-5502 4375);
DISPLAY 0.872340 (-5502 4375);
PAINT GREEN (-5502 4375);
DISPLAY INVISIBLE (-5502 4375);
FORCEADD TAP..6
(-5500 4425);
FORCEPROP 3 LASTPIN (-5450 4425) SIG_NAME M_D_DQ<58>
J 0
(-5440 4435);
DISPLAY 0.659574 (-5440 4435);
PAINT MONO (-5440 4435);
DISPLAY INVISIBLE (-5440 4435);
FORCEPROP 1 LASTPIN (-5450 4425) BN 58
J 0
(-5502 4433);
DISPLAY 0.617021 (-5502 4433);
PAINT PINK (-5502 4433);
FORCEPROP 2 LAST CDS_LIB mstr_standard
J 0
(-5500 4425);
PAINT MONO (-5500 4425);
DISPLAY INVISIBLE (-5500 4425);
FORCEPROP 1 LAST BODY_TYPE PLUMBING
J 0
(-5500 4375);
DISPLAY 1.595745 (-5500 4375);
PAINT GREEN (-5500 4375);
DISPLAY INVISIBLE (-5500 4375);
FORCEPROP 1 LAST HDL_TAP TRUE
J 0
(-5175 4300);
DISPLAY 1.595745 (-5175 4300);
PAINT GREEN (-5175 4300);
DISPLAY INVISIBLE (-5175 4300);
FORCEPROP 1 LAST PATH I81
J 0
(-5502 4425);
DISPLAY 0.872340 (-5502 4425);
PAINT GREEN (-5502 4425);
DISPLAY INVISIBLE (-5502 4425);
FORCEADD TAP..6
(-5500 4475);
FORCEPROP 3 LASTPIN (-5450 4475) SIG_NAME M_D_DQ<59>
J 0
(-5440 4485);
DISPLAY 0.659574 (-5440 4485);
PAINT MONO (-5440 4485);
DISPLAY INVISIBLE (-5440 4485);
FORCEPROP 1 LASTPIN (-5450 4475) BN 59
J 0
(-5502 4483);
DISPLAY 0.617021 (-5502 4483);
PAINT PINK (-5502 4483);
FORCEPROP 2 LAST CDS_LIB mstr_standard
J 0
(-5500 4475);
PAINT MONO (-5500 4475);
DISPLAY INVISIBLE (-5500 4475);
FORCEPROP 1 LAST BODY_TYPE PLUMBING
J 0
(-5500 4425);
DISPLAY 1.595745 (-5500 4425);
PAINT GREEN (-5500 4425);
DISPLAY INVISIBLE (-5500 4425);
FORCEPROP 1 LAST HDL_TAP TRUE
J 0
(-5175 4350);
DISPLAY 1.595745 (-5175 4350);
PAINT GREEN (-5175 4350);
DISPLAY INVISIBLE (-5175 4350);
FORCEPROP 1 LAST PATH I82
J 0
(-5502 4475);
DISPLAY 0.872340 (-5502 4475);
PAINT GREEN (-5502 4475);
DISPLAY INVISIBLE (-5502 4475);
FORCEADD TAP..6
(-5500 4525);
FORCEPROP 3 LASTPIN (-5450 4525) SIG_NAME M_D_DQ<60>
J 0
(-5440 4535);
DISPLAY 0.659574 (-5440 4535);
PAINT MONO (-5440 4535);
DISPLAY INVISIBLE (-5440 4535);
FORCEPROP 1 LASTPIN (-5450 4525) BN 60
J 0
(-5502 4533);
DISPLAY 0.617021 (-5502 4533);
PAINT PINK (-5502 4533);
FORCEPROP 2 LAST CDS_LIB mstr_standard
J 0
(-5500 4525);
PAINT MONO (-5500 4525);
DISPLAY INVISIBLE (-5500 4525);
FORCEPROP 1 LAST BODY_TYPE PLUMBING
J 0
(-5500 4475);
DISPLAY 1.595745 (-5500 4475);
PAINT GREEN (-5500 4475);
DISPLAY INVISIBLE (-5500 4475);
FORCEPROP 1 LAST HDL_TAP TRUE
J 0
(-5175 4400);
DISPLAY 1.595745 (-5175 4400);
PAINT GREEN (-5175 4400);
DISPLAY INVISIBLE (-5175 4400);
FORCEPROP 1 LAST PATH I83
J 0
(-5502 4525);
DISPLAY 0.872340 (-5502 4525);
PAINT GREEN (-5502 4525);
DISPLAY INVISIBLE (-5502 4525);
FORCEADD TAP..6
(-5500 4575);
FORCEPROP 3 LASTPIN (-5450 4575) SIG_NAME M_D_DQ<61>
J 0
(-5440 4585);
DISPLAY 0.659574 (-5440 4585);
PAINT MONO (-5440 4585);
DISPLAY INVISIBLE (-5440 4585);
FORCEPROP 1 LASTPIN (-5450 4575) BN 61
J 0
(-5502 4583);
DISPLAY 0.617021 (-5502 4583);
PAINT PINK (-5502 4583);
FORCEPROP 2 LAST CDS_LIB mstr_standard
J 0
(-5500 4575);
PAINT MONO (-5500 4575);
DISPLAY INVISIBLE (-5500 4575);
FORCEPROP 1 LAST BODY_TYPE PLUMBING
J 0
(-5500 4525);
DISPLAY 1.595745 (-5500 4525);
PAINT GREEN (-5500 4525);
DISPLAY INVISIBLE (-5500 4525);
FORCEPROP 1 LAST HDL_TAP TRUE
J 0
(-5175 4450);
DISPLAY 1.595745 (-5175 4450);
PAINT GREEN (-5175 4450);
DISPLAY INVISIBLE (-5175 4450);
FORCEPROP 1 LAST PATH I84
J 0
(-5502 4575);
DISPLAY 0.872340 (-5502 4575);
PAINT GREEN (-5502 4575);
DISPLAY INVISIBLE (-5502 4575);
FORCEADD TAP..6
(-5500 4625);
FORCEPROP 3 LASTPIN (-5450 4625) SIG_NAME M_D_DQ<62>
J 0
(-5440 4635);
DISPLAY 0.659574 (-5440 4635);
PAINT MONO (-5440 4635);
DISPLAY INVISIBLE (-5440 4635);
FORCEPROP 1 LASTPIN (-5450 4625) BN 62
J 0
(-5502 4633);
DISPLAY 0.617021 (-5502 4633);
PAINT PINK (-5502 4633);
FORCEPROP 2 LAST CDS_LIB mstr_standard
J 0
(-5500 4625);
PAINT MONO (-5500 4625);
DISPLAY INVISIBLE (-5500 4625);
FORCEPROP 1 LAST BODY_TYPE PLUMBING
J 0
(-5500 4575);
DISPLAY 1.595745 (-5500 4575);
PAINT GREEN (-5500 4575);
DISPLAY INVISIBLE (-5500 4575);
FORCEPROP 1 LAST HDL_TAP TRUE
J 0
(-5175 4500);
DISPLAY 1.595745 (-5175 4500);
PAINT GREEN (-5175 4500);
DISPLAY INVISIBLE (-5175 4500);
FORCEPROP 1 LAST PATH I85
J 0
(-5502 4625);
DISPLAY 0.872340 (-5502 4625);
PAINT GREEN (-5502 4625);
DISPLAY INVISIBLE (-5502 4625);
FORCEADD TAP..6
(-5500 4675);
FORCEPROP 3 LASTPIN (-5450 4675) SIG_NAME M_D_DQ<63>
J 0
(-5440 4685);
DISPLAY 0.659574 (-5440 4685);
PAINT MONO (-5440 4685);
DISPLAY INVISIBLE (-5440 4685);
FORCEPROP 1 LASTPIN (-5450 4675) BN 63
J 0
(-5502 4683);
DISPLAY 0.617021 (-5502 4683);
PAINT PINK (-5502 4683);
FORCEPROP 2 LAST CDS_LIB mstr_standard
J 0
(-5500 4675);
PAINT MONO (-5500 4675);
DISPLAY INVISIBLE (-5500 4675);
FORCEPROP 1 LAST BODY_TYPE PLUMBING
J 0
(-5500 4625);
DISPLAY 1.595745 (-5500 4625);
PAINT GREEN (-5500 4625);
DISPLAY INVISIBLE (-5500 4625);
FORCEPROP 1 LAST HDL_TAP TRUE
J 0
(-5175 4550);
DISPLAY 1.595745 (-5175 4550);
PAINT GREEN (-5175 4550);
DISPLAY INVISIBLE (-5175 4550);
FORCEPROP 1 LAST PATH I86
J 0
(-5502 4675);
DISPLAY 0.872340 (-5502 4675);
PAINT GREEN (-5502 4675);
DISPLAY INVISIBLE (-5502 4675);
FORCEADD TAP..6
R 2
(-2775 725);
FORCEPROP 3 LASTPIN (-2825 725) SIG_NAME M_D_BA<0>
J 0
(-2815 735);
DISPLAY 0.659574 (-2815 735);
PAINT MONO (-2815 735);
DISPLAY INVISIBLE (-2815 735);
FORCEPROP 1 LASTPIN (-2825 725) BN 0
J 2
(-2773 733);
DISPLAY 0.617021 (-2773 733);
PAINT PINK (-2773 733);
FORCEPROP 2 LAST CDS_LIB mstr_standard
J 0
(-2775 725);
PAINT MONO (-2775 725);
DISPLAY INVISIBLE (-2775 725);
FORCEPROP 1 LAST BODY_TYPE PLUMBING
J 2
(-2775 675);
DISPLAY 1.595745 (-2775 675);
PAINT GREEN (-2775 675);
DISPLAY INVISIBLE (-2775 675);
FORCEPROP 1 LAST HDL_TAP TRUE
J 2
(-3100 600);
DISPLAY 1.595745 (-3100 600);
PAINT GREEN (-3100 600);
DISPLAY INVISIBLE (-3100 600);
FORCEPROP 1 LAST PATH I87
J 2
(-2773 725);
DISPLAY 0.872340 (-2773 725);
PAINT GREEN (-2773 725);
DISPLAY INVISIBLE (-2773 725);
FORCEADD TAP..6
R 2
(-2775 775);
FORCEPROP 3 LASTPIN (-2825 775) SIG_NAME M_D_BA<1>
J 0
(-2815 785);
DISPLAY 0.659574 (-2815 785);
PAINT MONO (-2815 785);
DISPLAY INVISIBLE (-2815 785);
FORCEPROP 1 LASTPIN (-2825 775) BN 1
J 2
(-2773 783);
DISPLAY 0.617021 (-2773 783);
PAINT PINK (-2773 783);
FORCEPROP 2 LAST CDS_LIB mstr_standard
J 0
(-2775 775);
PAINT MONO (-2775 775);
DISPLAY INVISIBLE (-2775 775);
FORCEPROP 1 LAST BODY_TYPE PLUMBING
J 2
(-2775 725);
DISPLAY 1.595745 (-2775 725);
PAINT GREEN (-2775 725);
DISPLAY INVISIBLE (-2775 725);
FORCEPROP 1 LAST HDL_TAP TRUE
J 2
(-3100 650);
DISPLAY 1.595745 (-3100 650);
PAINT GREEN (-3100 650);
DISPLAY INVISIBLE (-3100 650);
FORCEPROP 1 LAST PATH I88
J 2
(-2773 775);
DISPLAY 0.872340 (-2773 775);
PAINT GREEN (-2773 775);
DISPLAY INVISIBLE (-2773 775);
FORCEADD TAP..6
R 2
(-2775 875);
FORCEPROP 3 LASTPIN (-2825 875) SIG_NAME M_D_BG<1>
J 0
(-2815 885);
DISPLAY 0.659574 (-2815 885);
PAINT MONO (-2815 885);
DISPLAY INVISIBLE (-2815 885);
FORCEPROP 1 LASTPIN (-2825 875) BN 1
J 2
(-2773 883);
DISPLAY 0.617021 (-2773 883);
PAINT PINK (-2773 883);
FORCEPROP 2 LAST CDS_LIB mstr_standard
J 0
(-2775 875);
PAINT MONO (-2775 875);
DISPLAY INVISIBLE (-2775 875);
FORCEPROP 1 LAST BODY_TYPE PLUMBING
J 2
(-2775 825);
DISPLAY 1.595745 (-2775 825);
PAINT GREEN (-2775 825);
DISPLAY INVISIBLE (-2775 825);
FORCEPROP 1 LAST HDL_TAP TRUE
J 2
(-3100 750);
DISPLAY 1.595745 (-3100 750);
PAINT GREEN (-3100 750);
DISPLAY INVISIBLE (-3100 750);
FORCEPROP 1 LAST PATH I89
J 2
(-2773 875);
DISPLAY 0.872340 (-2773 875);
PAINT GREEN (-2773 875);
DISPLAY INVISIBLE (-2773 875);
FORCEADD TAP..6
(-5500 825);
FORCEPROP 3 LASTPIN (-5450 825) SIG_NAME M_D_CLK_DP<0>
J 0
(-5440 835);
DISPLAY 0.659574 (-5440 835);
PAINT MONO (-5440 835);
DISPLAY INVISIBLE (-5440 835);
FORCEPROP 1 LASTPIN (-5450 825) BN 0
J 0
(-5502 833);
DISPLAY 0.617021 (-5502 833);
PAINT PINK (-5502 833);
FORCEPROP 2 LAST CDS_LIB mstr_standard
J 0
(-5500 825);
PAINT MONO (-5500 825);
DISPLAY INVISIBLE (-5500 825);
FORCEPROP 1 LAST BODY_TYPE PLUMBING
J 0
(-5500 775);
DISPLAY 1.595745 (-5500 775);
PAINT GREEN (-5500 775);
DISPLAY INVISIBLE (-5500 775);
FORCEPROP 1 LAST HDL_TAP TRUE
J 0
(-5175 700);
DISPLAY 1.595745 (-5175 700);
PAINT GREEN (-5175 700);
DISPLAY INVISIBLE (-5175 700);
FORCEPROP 1 LAST PATH I9
J 0
(-5502 825);
DISPLAY 0.872340 (-5502 825);
PAINT GREEN (-5502 825);
DISPLAY INVISIBLE (-5502 825);
FORCEADD TAP..6
R 2
(-2775 825);
FORCEPROP 3 LASTPIN (-2825 825) SIG_NAME M_D_BG<0>
J 0
(-2815 835);
DISPLAY 0.659574 (-2815 835);
PAINT MONO (-2815 835);
DISPLAY INVISIBLE (-2815 835);
FORCEPROP 1 LASTPIN (-2825 825) BN 0
J 2
(-2773 833);
DISPLAY 0.617021 (-2773 833);
PAINT PINK (-2773 833);
FORCEPROP 2 LAST CDS_LIB mstr_standard
J 0
(-2775 825);
PAINT MONO (-2775 825);
DISPLAY INVISIBLE (-2775 825);
FORCEPROP 1 LAST BODY_TYPE PLUMBING
J 2
(-2775 775);
DISPLAY 1.595745 (-2775 775);
PAINT GREEN (-2775 775);
DISPLAY INVISIBLE (-2775 775);
FORCEPROP 1 LAST HDL_TAP TRUE
J 2
(-3100 700);
DISPLAY 1.595745 (-3100 700);
PAINT GREEN (-3100 700);
DISPLAY INVISIBLE (-3100 700);
FORCEPROP 1 LAST PATH I90
J 2
(-2773 825);
DISPLAY 0.872340 (-2773 825);
PAINT GREEN (-2773 825);
DISPLAY INVISIBLE (-2773 825);
FORCEADD TAP..6
R 2
(-2775 1025);
FORCEPROP 3 LASTPIN (-2825 1025) SIG_NAME M_D_CS_N<1>
J 0
(-2815 1035);
DISPLAY 0.659574 (-2815 1035);
PAINT MONO (-2815 1035);
DISPLAY INVISIBLE (-2815 1035);
FORCEPROP 1 LASTPIN (-2825 1025) BN 1
J 2
(-2773 1033);
DISPLAY 0.617021 (-2773 1033);
PAINT PINK (-2773 1033);
FORCEPROP 2 LAST CDS_LIB mstr_standard
J 0
(-2775 1025);
PAINT MONO (-2775 1025);
DISPLAY INVISIBLE (-2775 1025);
FORCEPROP 1 LAST BODY_TYPE PLUMBING
J 2
(-2775 975);
DISPLAY 1.595745 (-2775 975);
PAINT GREEN (-2775 975);
DISPLAY INVISIBLE (-2775 975);
FORCEPROP 1 LAST HDL_TAP TRUE
J 2
(-3100 900);
DISPLAY 1.595745 (-3100 900);
PAINT GREEN (-3100 900);
DISPLAY INVISIBLE (-3100 900);
FORCEPROP 1 LAST PATH I91
J 2
(-2773 1025);
DISPLAY 0.872340 (-2773 1025);
PAINT GREEN (-2773 1025);
DISPLAY INVISIBLE (-2773 1025);
FORCEADD TAP..6
R 2
(-2775 975);
FORCEPROP 3 LASTPIN (-2825 975) SIG_NAME M_D_CS_N<0>
J 0
(-2815 985);
DISPLAY 0.659574 (-2815 985);
PAINT MONO (-2815 985);
DISPLAY INVISIBLE (-2815 985);
FORCEPROP 1 LASTPIN (-2825 975) BN 0
J 2
(-2773 983);
DISPLAY 0.617021 (-2773 983);
PAINT PINK (-2773 983);
FORCEPROP 2 LAST CDS_LIB mstr_standard
J 0
(-2775 975);
PAINT MONO (-2775 975);
DISPLAY INVISIBLE (-2775 975);
FORCEPROP 1 LAST BODY_TYPE PLUMBING
J 2
(-2775 925);
DISPLAY 1.595745 (-2775 925);
PAINT GREEN (-2775 925);
DISPLAY INVISIBLE (-2775 925);
FORCEPROP 1 LAST HDL_TAP TRUE
J 2
(-3100 850);
DISPLAY 1.595745 (-3100 850);
PAINT GREEN (-3100 850);
DISPLAY INVISIBLE (-3100 850);
FORCEPROP 1 LAST PATH I92
J 2
(-2773 975);
DISPLAY 0.872340 (-2773 975);
PAINT GREEN (-2773 975);
DISPLAY INVISIBLE (-2773 975);
FORCEADD TAP..6
R 2
(-2775 1075);
FORCEPROP 3 LASTPIN (-2825 1075) SIG_NAME M_D_CS_N<2>
J 0
(-2815 1085);
DISPLAY 0.659574 (-2815 1085);
PAINT MONO (-2815 1085);
DISPLAY INVISIBLE (-2815 1085);
FORCEPROP 1 LASTPIN (-2825 1075) BN 2
J 2
(-2773 1083);
DISPLAY 0.617021 (-2773 1083);
PAINT PINK (-2773 1083);
FORCEPROP 2 LAST CDS_LIB mstr_standard
J 0
(-2775 1075);
PAINT MONO (-2775 1075);
DISPLAY INVISIBLE (-2775 1075);
FORCEPROP 1 LAST BODY_TYPE PLUMBING
J 2
(-2775 1025);
DISPLAY 1.595745 (-2775 1025);
PAINT GREEN (-2775 1025);
DISPLAY INVISIBLE (-2775 1025);
FORCEPROP 1 LAST HDL_TAP TRUE
J 2
(-3100 950);
DISPLAY 1.595745 (-3100 950);
PAINT GREEN (-3100 950);
DISPLAY INVISIBLE (-3100 950);
FORCEPROP 1 LAST PATH I93
J 2
(-2773 1075);
DISPLAY 0.872340 (-2773 1075);
PAINT GREEN (-2773 1075);
DISPLAY INVISIBLE (-2773 1075);
FORCEADD TAP..6
R 2
(-2775 1175);
FORCEPROP 3 LASTPIN (-2825 1175) SIG_NAME M_D_CS_N<4>
J 0
(-2815 1185);
DISPLAY 0.659574 (-2815 1185);
PAINT MONO (-2815 1185);
DISPLAY INVISIBLE (-2815 1185);
FORCEPROP 1 LASTPIN (-2825 1175) BN 4
J 2
(-2773 1183);
DISPLAY 0.617021 (-2773 1183);
PAINT PINK (-2773 1183);
FORCEPROP 2 LAST CDS_LIB mstr_standard
J 0
(-2775 1175);
PAINT MONO (-2775 1175);
DISPLAY INVISIBLE (-2775 1175);
FORCEPROP 1 LAST BODY_TYPE PLUMBING
J 2
(-2775 1125);
DISPLAY 1.595745 (-2775 1125);
PAINT GREEN (-2775 1125);
DISPLAY INVISIBLE (-2775 1125);
FORCEPROP 1 LAST HDL_TAP TRUE
J 2
(-3100 1050);
DISPLAY 1.595745 (-3100 1050);
PAINT GREEN (-3100 1050);
DISPLAY INVISIBLE (-3100 1050);
FORCEPROP 1 LAST PATH I94
J 2
(-2773 1175);
DISPLAY 0.872340 (-2773 1175);
PAINT GREEN (-2773 1175);
DISPLAY INVISIBLE (-2773 1175);
FORCEADD TAP..6
R 2
(-2775 1125);
FORCEPROP 3 LASTPIN (-2825 1125) SIG_NAME M_D_CS_N<3>
J 0
(-2815 1135);
DISPLAY 0.659574 (-2815 1135);
PAINT MONO (-2815 1135);
DISPLAY INVISIBLE (-2815 1135);
FORCEPROP 1 LASTPIN (-2825 1125) BN 3
J 2
(-2773 1133);
DISPLAY 0.617021 (-2773 1133);
PAINT PINK (-2773 1133);
FORCEPROP 2 LAST CDS_LIB mstr_standard
J 0
(-2775 1125);
PAINT MONO (-2775 1125);
DISPLAY INVISIBLE (-2775 1125);
FORCEPROP 1 LAST BODY_TYPE PLUMBING
J 2
(-2775 1075);
DISPLAY 1.595745 (-2775 1075);
PAINT GREEN (-2775 1075);
DISPLAY INVISIBLE (-2775 1075);
FORCEPROP 1 LAST HDL_TAP TRUE
J 2
(-3100 1000);
DISPLAY 1.595745 (-3100 1000);
PAINT GREEN (-3100 1000);
DISPLAY INVISIBLE (-3100 1000);
FORCEPROP 1 LAST PATH I95
J 2
(-2773 1125);
DISPLAY 0.872340 (-2773 1125);
PAINT GREEN (-2773 1125);
DISPLAY INVISIBLE (-2773 1125);
FORCEADD TAP..6
R 2
(-2775 1325);
FORCEPROP 3 LASTPIN (-2825 1325) SIG_NAME M_D_CS_N<7>
J 0
(-2815 1335);
DISPLAY 0.659574 (-2815 1335);
PAINT MONO (-2815 1335);
DISPLAY INVISIBLE (-2815 1335);
FORCEPROP 1 LASTPIN (-2825 1325) BN 7
J 2
(-2773 1333);
DISPLAY 0.617021 (-2773 1333);
PAINT PINK (-2773 1333);
FORCEPROP 2 LAST CDS_LIB mstr_standard
J 0
(-2775 1325);
PAINT MONO (-2775 1325);
DISPLAY INVISIBLE (-2775 1325);
FORCEPROP 1 LAST BODY_TYPE PLUMBING
J 2
(-2775 1275);
DISPLAY 1.595745 (-2775 1275);
PAINT GREEN (-2775 1275);
DISPLAY INVISIBLE (-2775 1275);
FORCEPROP 1 LAST HDL_TAP TRUE
J 2
(-3100 1200);
DISPLAY 1.595745 (-3100 1200);
PAINT GREEN (-3100 1200);
DISPLAY INVISIBLE (-3100 1200);
FORCEPROP 1 LAST PATH I96
J 2
(-2773 1325);
DISPLAY 0.872340 (-2773 1325);
PAINT GREEN (-2773 1325);
DISPLAY INVISIBLE (-2773 1325);
FORCEADD TAP..6
R 2
(-2775 1225);
FORCEPROP 3 LASTPIN (-2825 1225) SIG_NAME M_D_CS_N<5>
J 0
(-2815 1235);
DISPLAY 0.659574 (-2815 1235);
PAINT MONO (-2815 1235);
DISPLAY INVISIBLE (-2815 1235);
FORCEPROP 1 LASTPIN (-2825 1225) BN 5
J 2
(-2773 1233);
DISPLAY 0.617021 (-2773 1233);
PAINT PINK (-2773 1233);
FORCEPROP 2 LAST CDS_LIB mstr_standard
J 0
(-2775 1225);
PAINT MONO (-2775 1225);
DISPLAY INVISIBLE (-2775 1225);
FORCEPROP 1 LAST BODY_TYPE PLUMBING
J 2
(-2775 1175);
DISPLAY 1.595745 (-2775 1175);
PAINT GREEN (-2775 1175);
DISPLAY INVISIBLE (-2775 1175);
FORCEPROP 1 LAST HDL_TAP TRUE
J 2
(-3100 1100);
DISPLAY 1.595745 (-3100 1100);
PAINT GREEN (-3100 1100);
DISPLAY INVISIBLE (-3100 1100);
FORCEPROP 1 LAST PATH I97
J 2
(-2773 1225);
DISPLAY 0.872340 (-2773 1225);
PAINT GREEN (-2773 1225);
DISPLAY INVISIBLE (-2773 1225);
FORCEADD TAP..6
R 2
(-2775 1275);
FORCEPROP 3 LASTPIN (-2825 1275) SIG_NAME M_D_CS_N<6>
J 0
(-2815 1285);
DISPLAY 0.659574 (-2815 1285);
PAINT MONO (-2815 1285);
DISPLAY INVISIBLE (-2815 1285);
FORCEPROP 1 LASTPIN (-2825 1275) BN 6
J 2
(-2773 1283);
DISPLAY 0.617021 (-2773 1283);
PAINT PINK (-2773 1283);
FORCEPROP 2 LAST CDS_LIB mstr_standard
J 0
(-2775 1275);
PAINT MONO (-2775 1275);
DISPLAY INVISIBLE (-2775 1275);
FORCEPROP 1 LAST BODY_TYPE PLUMBING
J 2
(-2775 1225);
DISPLAY 1.595745 (-2775 1225);
PAINT GREEN (-2775 1225);
DISPLAY INVISIBLE (-2775 1225);
FORCEPROP 1 LAST HDL_TAP TRUE
J 2
(-3100 1150);
DISPLAY 1.595745 (-3100 1150);
PAINT GREEN (-3100 1150);
DISPLAY INVISIBLE (-3100 1150);
FORCEPROP 1 LAST PATH I98
J 2
(-2773 1275);
DISPLAY 0.872340 (-2773 1275);
PAINT GREEN (-2773 1275);
DISPLAY INVISIBLE (-2773 1275);
FORCEADD TAP..6
R 2
(-2775 1425);
FORCEPROP 3 LASTPIN (-2825 1425) SIG_NAME M_D_ODT<0>
J 0
(-2815 1435);
DISPLAY 0.659574 (-2815 1435);
PAINT MONO (-2815 1435);
DISPLAY INVISIBLE (-2815 1435);
FORCEPROP 1 LASTPIN (-2825 1425) BN 0
J 2
(-2773 1433);
DISPLAY 0.617021 (-2773 1433);
PAINT PINK (-2773 1433);
FORCEPROP 2 LAST CDS_LIB mstr_standard
J 0
(-2775 1425);
PAINT MONO (-2775 1425);
DISPLAY INVISIBLE (-2775 1425);
FORCEPROP 1 LAST BODY_TYPE PLUMBING
J 2
(-2775 1375);
DISPLAY 1.595745 (-2775 1375);
PAINT GREEN (-2775 1375);
DISPLAY INVISIBLE (-2775 1375);
FORCEPROP 1 LAST HDL_TAP TRUE
J 2
(-3100 1300);
DISPLAY 1.595745 (-3100 1300);
PAINT GREEN (-3100 1300);
DISPLAY INVISIBLE (-3100 1300);
FORCEPROP 1 LAST PATH I99
J 2
(-2773 1425);
DISPLAY 0.872340 (-2773 1425);
PAINT GREEN (-2773 1425);
DISPLAY INVISIBLE (-2773 1425);
FORCEADD DESIGN_NOTE..1
(-6525 400);
FORCEPROP 0 LAST L1 CPU SYMBOLS 1-30 ARE PRELIMINARY AND SUBJECT TO CHANGE
J 0
(-6725 275);
DISPLAY 1.021277 (-6725 275);
PAINT ORANGE (-6725 275);
FORCEPROP 2 LAST CDS_LIB mstr_symbols
J 0
(-6525 400);
PAINT ORANGE (-6525 400);
DISPLAY INVISIBLE (-6525 400);
FORCEPROP 1 LAST COMMENT_BODY TRUE
J 0
(-6500 500);
DISPLAY 0.978723 (-6500 500);
PAINT ORANGE (-6500 500);
DISPLAY INVISIBLE (-6500 500);
FORCEADD PRELIM..10
(-4140 2565);
PAINT GRAY (-4140 2565);
FORCEPROP 2 LAST CDS_LIB mstr_misc
J 0
(-4140 2565);
PAINT ORANGE (-4140 2565);
DISPLAY INVISIBLE (-4140 2565);
FORCEPROP 1 LAST COMMENT_BODY TRUE
J 0
(-4140 2565);
PAINT ORANGE (-4140 2565);
DISPLAY INVISIBLE (-4140 2565);
FORCEADD INTEL_CORP_BPAGE..1
(0 0);
FORCEPROP 1 LAST CDS_CON_LAST_MODIFIED Tue Dec 01 11:51:18 2015
J 0
(-1425 325);
DISPLAY 1.340426 (-1425 325);
PAINT GREEN (-1425 325);
DISPLAY INVISIBLE (-1425 325);
FORCEPROP 1 LAST CUSTOM_TXT_CDS <CURRENT_DESIGN_SHEET> OF <TOTAL_DESIGN_SHEETS>
J 0
(-500 25);
PAINT GREEN (-500 25);
FORCEPROP 1 LAST CUSTOM_TXT_CDS <CON_LAST_MODIFIED>
J 0
(-1925 350);
PAINT GREEN (-1925 350);
FORCEPROP 2 LAST CUSTOM_TXT_CDS <XR_PAGE_TITLE>
J 0
(-7890 5250);
DISPLAY 0.638298 (-7890 5250);
PAINT PINK (-7890 5250);
DISPLAY INVISIBLE (-7890 5250);
FORCEPROP 1 LAST SCH_ADDRESS3 Santa Clara, CA 95052-8119
J 0
(-3975 25);
DISPLAY 0.617021 (-3975 25);
PAINT GREEN (-3975 25);
FORCEPROP 1 LAST SCH_ADDRESS2 P.O. BOX 58119
J 0
(-3975 75);
DISPLAY 0.617021 (-3975 75);
PAINT GREEN (-3975 75);
FORCEPROP 1 LAST SCH_ADDRESS1 2200 Mission College Blvd.
J 0
(-3975 125);
DISPLAY 0.617021 (-3975 125);
PAINT GREEN (-3975 125);
FORCEPROP 1 LAST SCH_TITLE SKYLAKE - SKT0 - 6 OF 21
J 0
(-7950 50);
DISPLAY 1.212766 (-7950 50);
PAINT GREEN (-7950 50);
FORCEPROP 1 LAST SCH_NUMBER H4694802
J 0
(-1300 150);
DISPLAY 1.212766 (-1300 150);
PAINT YELLOW (-1300 150);
FORCEPROP 1 LAST SCH_DEPT BESD
J 1
(-4450 100);
DISPLAY 1.212766 (-4450 100);
PAINT YELLOW (-4450 100);
FORCEPROP 1 LAST SCH_REV 2.420
J 0
(-250 150);
DISPLAY 0.978723 (-250 150);
PAINT YELLOW (-250 150);
FORCEPROP 2 LAST CDS_LIB mstr_symbols
J 0
(0 0);
PAINT ORANGE (0 0);
DISPLAY INVISIBLE (0 0);
FORCEPROP 2 LAST PAGE_BORDER TRUE
J 0
(-7890 5250);
DISPLAY 0.851064 (-7890 5250);
PAINT PINK (-7890 5250);
DISPLAY INVISIBLE (-7890 5250);
FORCEPROP 1 LAST COMMENT_BODY TRUE
J 0
(12 12);
DISPLAY 0.638298 (12 12);
PAINT GREEN (12 12);
DISPLAY INVISIBLE (12 12);
FORCEPROP 2 LAST CDS_XR_PAGE_TITLE CR-26 : @BASEBOARD_FAB2_LIB.BASEBOARD_FAB2(SCH_1):PAGE26
J 0
(-7890 5250);
DISPLAY 0.638298 (-7890 5250);
PAINT PINK (-7890 5250);
DISPLAY INVISIBLE (-7890 5250);
WIRE 17 -1 (-2725 4700)(-2725 4750);
WIRE 17 -1 (-2725 4650)(-2725 4700);
WIRE 17 -1 (-1975 4750)(-2725 4750);
FORCEPROP 2 LAST SIG_NAME M_D_DQS_DP<17:0>
J 0
(-2625 4760);
DISPLAY 0.617021 (-2625 4760);
PAINT ORANGE (-2625 4760);
WIRE 17 -1 (-2725 4600)(-2725 4650);
WIRE 17 -1 (-2725 4550)(-2725 4600);
WIRE 17 -1 (-2725 4500)(-2725 4550);
WIRE 17 -1 (-2725 4450)(-2725 4500);
WIRE 17 -1 (-2725 4400)(-2725 4450);
WIRE 17 -1 (-2725 4350)(-2725 4400);
WIRE 17 -1 (-2725 4300)(-2725 4350);
WIRE 17 -1 (-2725 4250)(-2725 4300);
WIRE 17 -1 (-2725 4200)(-2725 4250);
WIRE 17 -1 (-2725 4150)(-2725 4200);
WIRE 17 -1 (-2725 4100)(-2725 4150);
WIRE 17 -1 (-2725 4050)(-2725 4100);
WIRE 17 -1 (-2725 4000)(-2725 4050);
WIRE 17 -1 (-2725 3950)(-2725 4000);
WIRE 17 -1 (-2725 3900)(-2725 3950);
WIRE 17 -1 (-2725 3850)(-2725 3900);
WIRE 17 -1 (-2725 3750)(-2725 3775);
WIRE 17 -1 (-2725 3700)(-2725 3750);
WIRE 17 -1 (-1975 3775)(-2725 3775);
FORCEPROP 2 LAST SIG_NAME M_D_DQS_DN<17:0>
J 0
(-2625 3785);
DISPLAY 0.617021 (-2625 3785);
PAINT ORANGE (-2625 3785);
WIRE 17 -1 (-2725 3650)(-2725 3700);
WIRE 17 -1 (-2725 3600)(-2725 3650);
WIRE 17 -1 (-2725 3550)(-2725 3600);
WIRE 17 -1 (-2725 3500)(-2725 3550);
WIRE 17 -1 (-2725 3450)(-2725 3500);
WIRE 17 -1 (-2725 3400)(-2725 3450);
WIRE 17 -1 (-2725 3350)(-2725 3400);
WIRE 17 -1 (-2725 3300)(-2725 3350);
WIRE 17 -1 (-2725 3250)(-2725 3300);
WIRE 17 -1 (-2725 3200)(-2725 3250);
WIRE 17 -1 (-2725 3150)(-2725 3200);
WIRE 17 -1 (-2725 3100)(-2725 3150);
WIRE 17 -1 (-2725 3050)(-2725 3100);
WIRE 17 -1 (-2725 3000)(-2725 3050);
WIRE 17 -1 (-2725 2950)(-2725 3000);
WIRE 17 -1 (-2725 2900)(-2725 2950);
WIRE 17 -1 (-2725 2800)(-2725 2825);
WIRE 17 -1 (-2725 2750)(-2725 2800);
WIRE 17 -1 (-1975 2825)(-2725 2825);
FORCEPROP 2 LAST SIG_NAME M_D_MA<17:0>
J 0
(-2625 2835);
DISPLAY 0.617021 (-2625 2835);
PAINT ORANGE (-2625 2835);
WIRE 17 -1 (-2725 2700)(-2725 2750);
WIRE 17 -1 (-2725 2650)(-2725 2700);
WIRE 17 -1 (-2725 2600)(-2725 2650);
WIRE 17 -1 (-2725 2550)(-2725 2600);
WIRE 17 -1 (-2725 2500)(-2725 2550);
WIRE 17 -1 (-2725 2450)(-2725 2500);
WIRE 17 -1 (-2725 2400)(-2725 2450);
WIRE 17 -1 (-2725 2350)(-2725 2400);
WIRE 17 -1 (-2725 2300)(-2725 2350);
WIRE 17 -1 (-2725 2250)(-2725 2300);
WIRE 17 -1 (-2725 2200)(-2725 2250);
WIRE 17 -1 (-2725 2150)(-2725 2200);
WIRE 17 -1 (-2725 2100)(-2725 2150);
WIRE 17 -1 (-2725 2050)(-2725 2100);
WIRE 17 -1 (-2725 2000)(-2725 2050);
WIRE 17 -1 (-2725 1950)(-2725 2000);
WIRE 17 -1 (-2725 800)(-2725 825);
WIRE 17 -1 (-2725 750)(-2725 800);
WIRE 17 -1 (-1975 825)(-2725 825);
FORCEPROP 2 LAST SIG_NAME M_D_BA<1:0>
J 0
(-2625 835);
DISPLAY 0.617021 (-2625 835);
PAINT ORANGE (-2625 835);
WIRE 17 -1 (-2725 900)(-2725 925);
WIRE 17 -1 (-2725 850)(-2725 900);
WIRE 17 -1 (-1975 925)(-2725 925);
FORCEPROP 2 LAST SIG_NAME M_D_BG<1:0>
J 0
(-2625 935);
DISPLAY 0.617021 (-2625 935);
PAINT ORANGE (-2625 935);
WIRE 17 -1 (-2725 1850)(-2725 1875);
WIRE 17 -1 (-2725 1800)(-2725 1850);
WIRE 17 -1 (-1975 1875)(-2725 1875);
FORCEPROP 2 LAST SIG_NAME M_D_CKE<3:0>
J 0
(-2625 1885);
DISPLAY 0.617021 (-2625 1885);
PAINT ORANGE (-2625 1885);
WIRE 17 -1 (-2725 1750)(-2725 1800);
WIRE 17 -1 (-2725 1700)(-2725 1750);
WIRE 17 -1 (-2725 1350)(-2725 1375);
WIRE 17 -1 (-2725 1300)(-2725 1350);
WIRE 17 -1 (-1975 1375)(-2725 1375);
FORCEPROP 2 LAST SIG_NAME M_D_CS_N<7:0>
J 0
(-2625 1385);
DISPLAY 0.617021 (-2625 1385);
PAINT ORANGE (-2625 1385);
WIRE 17 -1 (-2725 1250)(-2725 1300);
WIRE 17 -1 (-2725 1200)(-2725 1250);
WIRE 17 -1 (-2725 1150)(-2725 1200);
WIRE 17 -1 (-2725 1100)(-2725 1150);
WIRE 17 -1 (-2725 1050)(-2725 1100);
WIRE 17 -1 (-2725 1000)(-2725 1050);
WIRE 17 -1 (-2725 1600)(-2725 1625);
WIRE 17 -1 (-2725 1550)(-2725 1600);
WIRE 17 -1 (-1975 1625)(-2725 1625);
FORCEPROP 2 LAST SIG_NAME M_D_ODT<3:0>
J 0
(-2625 1635);
DISPLAY 0.617021 (-2625 1635);
PAINT ORANGE (-2625 1635);
WIRE 17 -1 (-2725 1500)(-2725 1550);
WIRE 17 -1 (-2725 1450)(-2725 1500);
WIRE 17 -1 (-5550 4650)(-5550 4700);
WIRE 17 -1 (-5550 4600)(-5550 4650);
WIRE 17 -1 (-5550 4700)(-5550 4800);
WIRE 17 -1 (-5550 4800)(-6300 4800);
FORCEPROP 2 LAST SIG_NAME M_D_DQ<63:0>
J 0
(-6250 4810);
DISPLAY 0.617021 (-6250 4810);
PAINT ORANGE (-6250 4810);
WIRE 17 -1 (-5550 4550)(-5550 4600);
WIRE 17 -1 (-5550 4500)(-5550 4550);
WIRE 17 -1 (-5550 4450)(-5550 4500);
WIRE 17 -1 (-5550 4400)(-5550 4450);
WIRE 17 -1 (-5550 4350)(-5550 4400);
WIRE 17 -1 (-5550 4300)(-5550 4350);
WIRE 17 -1 (-5550 4250)(-5550 4300);
WIRE 17 -1 (-5550 4200)(-5550 4250);
WIRE 17 -1 (-5550 4150)(-5550 4200);
WIRE 17 -1 (-5550 4100)(-5550 4150);
WIRE 17 -1 (-5550 4050)(-5550 4100);
WIRE 17 -1 (-5550 4000)(-5550 4050);
WIRE 17 -1 (-5550 3950)(-5550 4000);
WIRE 17 -1 (-5550 3900)(-5550 3950);
WIRE 17 -1 (-5550 3850)(-5550 3900);
WIRE 17 -1 (-5550 3800)(-5550 3850);
WIRE 17 -1 (-5550 3750)(-5550 3800);
WIRE 17 -1 (-5550 3700)(-5550 3750);
WIRE 17 -1 (-5550 3650)(-5550 3700);
WIRE 17 -1 (-5550 3600)(-5550 3650);
WIRE 17 -1 (-5550 3550)(-5550 3600);
WIRE 17 -1 (-5550 3500)(-5550 3550);
WIRE 17 -1 (-5550 3450)(-5550 3500);
WIRE 17 -1 (-5550 3400)(-5550 3450);
WIRE 17 -1 (-5550 3350)(-5550 3400);
WIRE 17 -1 (-5550 3300)(-5550 3350);
WIRE 17 -1 (-5550 3250)(-5550 3300);
WIRE 17 -1 (-5550 3200)(-5550 3250);
WIRE 17 -1 (-5550 3150)(-5550 3200);
WIRE 17 -1 (-5550 3100)(-5550 3150);
WIRE 17 -1 (-5550 3050)(-5550 3100);
WIRE 17 -1 (-5550 3000)(-5550 3050);
WIRE 17 -1 (-5550 2950)(-5550 3000);
WIRE 17 -1 (-5550 2900)(-5550 2950);
WIRE 17 -1 (-5550 2850)(-5550 2900);
WIRE 17 -1 (-5550 2800)(-5550 2850);
WIRE 17 -1 (-5550 2750)(-5550 2800);
WIRE 17 -1 (-5550 2700)(-5550 2750);
WIRE 17 -1 (-5550 2650)(-5550 2700);
WIRE 17 -1 (-5550 2600)(-5550 2650);
WIRE 17 -1 (-5550 2550)(-5550 2600);
WIRE 17 -1 (-5550 2500)(-5550 2550);
WIRE 17 -1 (-5550 2450)(-5550 2500);
WIRE 17 -1 (-5550 2400)(-5550 2450);
WIRE 17 -1 (-5550 2350)(-5550 2400);
WIRE 17 -1 (-5550 2300)(-5550 2350);
WIRE 17 -1 (-5550 2250)(-5550 2300);
WIRE 17 -1 (-5550 2200)(-5550 2250);
WIRE 17 -1 (-5550 2150)(-5550 2200);
WIRE 17 -1 (-5550 2100)(-5550 2150);
WIRE 17 -1 (-5550 2050)(-5550 2100);
WIRE 17 -1 (-5550 2000)(-5550 2050);
WIRE 17 -1 (-5550 1950)(-5550 2000);
WIRE 17 -1 (-5550 1900)(-5550 1950);
WIRE 17 -1 (-5550 1850)(-5550 1900);
WIRE 17 -1 (-5550 1800)(-5550 1850);
WIRE 17 -1 (-5550 1750)(-5550 1800);
WIRE 17 -1 (-5550 1700)(-5550 1750);
WIRE 17 -1 (-5550 1650)(-5550 1700);
WIRE 17 -1 (-5550 1600)(-5550 1650);
WIRE 17 -1 (-5550 1550)(-5550 1600);
WIRE 17 -1 (-5550 800)(-5550 825);
WIRE 17 -1 (-5550 750)(-5550 800);
WIRE 17 -1 (-5550 825)(-6300 825);
FORCEPROP 2 LAST SIG_NAME M_D_CLK_DN<3:0>
J 0
(-6250 835);
DISPLAY 0.617021 (-6250 835);
PAINT ORANGE (-6250 835);
WIRE 17 -1 (-5550 700)(-5550 750);
WIRE 17 -1 (-5550 650)(-5550 700);
WIRE 17 -1 (-5550 1000)(-5550 1025);
WIRE 17 -1 (-5550 950)(-5550 1000);
WIRE 17 -1 (-5550 1025)(-6300 1025);
FORCEPROP 2 LAST SIG_NAME M_D_CLK_DP<3:0>
J 0
(-6250 1035);
DISPLAY 0.617021 (-6250 1035);
PAINT ORANGE (-6250 1035);
WIRE 17 -1 (-5550 900)(-5550 950);
WIRE 17 -1 (-5550 850)(-5550 900);
WIRE 17 -1 (-5550 1450)(-5550 1475);
WIRE 17 -1 (-5550 1400)(-5550 1450);
WIRE 17 -1 (-5550 1475)(-6300 1475);
FORCEPROP 2 LAST SIG_NAME M_D_ECC<7:0>
J 0
(-6250 1485);
DISPLAY 0.617021 (-6250 1485);
PAINT ORANGE (-6250 1485);
WIRE 17 -1 (-5550 1350)(-5550 1400);
WIRE 17 -1 (-5550 1300)(-5550 1350);
WIRE 17 -1 (-5550 1250)(-5550 1300);
WIRE 17 -1 (-5550 1200)(-5550 1250);
WIRE 17 -1 (-5550 1150)(-5550 1200);
WIRE 17 -1 (-5550 1100)(-5550 1150);
WIRE 16 -1 (-5450 1775)(-4950 1775);
WIRE 16 -1 (-4950 525)(-6300 525);
FORCEPROP 2 LAST SIG_NAME M_D_C<2>
J 0
(-6250 535);
DISPLAY 0.617021 (-6250 535);
PAINT ORANGE (-6250 535);
WIRE 16 -1 (-4950 1075)(-5450 1075);
WIRE 16 -1 (-4950 1125)(-5450 1125);
WIRE 16 -1 (-4950 1175)(-5450 1175);
WIRE 16 -1 (-4950 1225)(-5450 1225);
WIRE 16 -1 (-4950 1275)(-5450 1275);
WIRE 16 -1 (-4950 1325)(-5450 1325);
WIRE 16 -1 (-4950 1375)(-5450 1375);
WIRE 16 -1 (-4950 1425)(-5450 1425);
WIRE 16 -1 (-5450 1525)(-4950 1525);
WIRE 16 -1 (-5450 1575)(-4950 1575);
WIRE 16 -1 (-5450 1625)(-4950 1625);
WIRE 16 -1 (-4950 1675)(-5450 1675);
WIRE 16 -1 (-5450 1725)(-4950 1725);
WIRE 16 -1 (-4950 1825)(-5450 1825);
WIRE 16 -1 (-5450 1875)(-4950 1875);
WIRE 16 -1 (-5450 1925)(-4950 1925);
WIRE 16 -1 (-5450 1975)(-4950 1975);
WIRE 16 -1 (-5450 2025)(-4950 2025);
WIRE 16 -1 (-4950 825)(-5450 825);
WIRE 16 -1 (-4950 875)(-5450 875);
WIRE 16 -1 (-4950 925)(-5450 925);
WIRE 16 -1 (-4950 975)(-5450 975);
WIRE 16 -1 (-4950 625)(-5450 625);
WIRE 16 -1 (-4950 675)(-5450 675);
WIRE 16 -1 (-4950 725)(-5450 725);
WIRE 16 -1 (-4950 775)(-5450 775);
WIRE 16 -1 (-5450 2075)(-4950 2075);
WIRE 16 -1 (-5450 2125)(-4950 2125);
WIRE 16 -1 (-5450 2175)(-4950 2175);
WIRE 16 -1 (-5450 2225)(-4950 2225);
WIRE 16 -1 (-4950 2275)(-5450 2275);
WIRE 16 -1 (-5450 2325)(-4950 2325);
WIRE 16 -1 (-5450 2375)(-4950 2375);
WIRE 16 -1 (-4950 2425)(-5450 2425);
WIRE 16 -1 (-5450 2475)(-4950 2475);
WIRE 16 -1 (-5450 2525)(-4950 2525);
WIRE 16 -1 (-5450 2575)(-4950 2575);
WIRE 16 -1 (-5450 2625)(-4950 2625);
WIRE 16 -1 (-4950 2675)(-5450 2675);
WIRE 16 -1 (-5450 2725)(-4950 2725);
WIRE 16 -1 (-5450 2775)(-4950 2775);
WIRE 16 -1 (-5450 2825)(-4950 2825);
WIRE 16 -1 (-5450 2875)(-4950 2875);
WIRE 16 -1 (-5450 2925)(-4950 2925);
WIRE 16 -1 (-5450 2975)(-4950 2975);
WIRE 16 -1 (-4950 3025)(-5450 3025);
WIRE 16 -1 (-5450 3075)(-4950 3075);
WIRE 16 -1 (-5450 3125)(-4950 3125);
WIRE 16 -1 (-5450 3175)(-4950 3175);
WIRE 16 -1 (-5450 3225)(-4950 3225);
WIRE 16 -1 (-5450 3275)(-4950 3275);
WIRE 16 -1 (-5450 3325)(-4950 3325);
WIRE 16 -1 (-4950 3375)(-5450 3375);
WIRE 16 -1 (-5450 3425)(-4950 3425);
WIRE 16 -1 (-5450 3475)(-4950 3475);
WIRE 16 -1 (-4950 3525)(-5450 3525);
WIRE 16 -1 (-5450 3575)(-4950 3575);
WIRE 16 -1 (-5450 3625)(-4950 3625);
WIRE 16 -1 (-4950 3675)(-5450 3675);
WIRE 16 -1 (-4950 3725)(-5450 3725);
WIRE 16 -1 (-4950 3775)(-5450 3775);
WIRE 16 -1 (-4950 3825)(-5450 3825);
WIRE 16 -1 (-4950 3875)(-5450 3875);
WIRE 16 -1 (-4950 3925)(-5450 3925);
WIRE 16 -1 (-4950 3975)(-5450 3975);
WIRE 16 -1 (-4950 4025)(-5450 4025);
WIRE 16 -1 (-4950 4075)(-5450 4075);
WIRE 16 -1 (-4950 4125)(-5450 4125);
WIRE 16 -1 (-4950 4175)(-5450 4175);
WIRE 16 -1 (-4950 4225)(-5450 4225);
WIRE 16 -1 (-4950 4275)(-5450 4275);
WIRE 16 -1 (-4950 4325)(-5450 4325);
WIRE 16 -1 (-4950 4375)(-5450 4375);
WIRE 16 -1 (-4950 4425)(-5450 4425);
WIRE 16 -1 (-4950 4475)(-5450 4475);
WIRE 16 -1 (-4950 4525)(-5450 4525);
WIRE 16 -1 (-4950 4575)(-5450 4575);
WIRE 16 -1 (-4950 4625)(-5450 4625);
WIRE 16 -1 (-4950 4675)(-5450 4675);
WIRE 16 -1 (-3250 1425)(-2825 1425);
WIRE 16 -1 (-3250 1475)(-2825 1475);
WIRE 16 -1 (-3250 1525)(-2825 1525);
WIRE 16 -1 (-3250 1575)(-2825 1575);
WIRE 16 -1 (-3250 1925)(-2825 1925);
WIRE 16 -1 (-3250 1975)(-2825 1975);
WIRE 16 -1 (-3250 2025)(-2825 2025);
WIRE 16 -1 (-3250 975)(-2825 975);
WIRE 16 -1 (-3250 1025)(-2825 1025);
WIRE 16 -1 (-3250 1075)(-2825 1075);
WIRE 16 -1 (-3250 1125)(-2825 1125);
WIRE 16 -1 (-3250 1175)(-2825 1175);
WIRE 16 -1 (-3250 1225)(-2825 1225);
WIRE 16 -1 (-3250 1275)(-2825 1275);
WIRE 16 -1 (-3250 1325)(-2825 1325);
WIRE 16 -1 (-3250 1675)(-2825 1675);
WIRE 16 -1 (-3250 1725)(-2825 1725);
WIRE 16 -1 (-3250 1775)(-2825 1775);
WIRE 16 -1 (-3250 1825)(-2825 1825);
WIRE 16 -1 (-3250 825)(-2825 825);
WIRE 16 -1 (-3250 875)(-2825 875);
WIRE 16 -1 (-3250 725)(-2825 725);
WIRE 16 -1 (-3250 775)(-2825 775);
WIRE 16 -1 (-3250 2075)(-2825 2075);
WIRE 16 -1 (-3250 2125)(-2825 2125);
WIRE 16 -1 (-3250 2175)(-2825 2175);
WIRE 16 -1 (-3250 2225)(-2825 2225);
WIRE 16 -1 (-3250 2275)(-2825 2275);
WIRE 16 -1 (-3250 2325)(-2825 2325);
WIRE 16 -1 (-3250 2375)(-2825 2375);
WIRE 16 -1 (-3250 2425)(-2825 2425);
WIRE 16 -1 (-3250 2475)(-2825 2475);
WIRE 16 -1 (-3250 2525)(-2825 2525);
WIRE 16 -1 (-3250 2575)(-2825 2575);
WIRE 16 -1 (-3250 2625)(-2825 2625);
WIRE 16 -1 (-3250 2675)(-2825 2675);
WIRE 16 -1 (-3250 2725)(-2825 2725);
WIRE 16 -1 (-3250 2775)(-2825 2775);
WIRE 16 -1 (-3250 3825)(-2825 3825);
WIRE 16 -1 (-3250 3875)(-2825 3875);
WIRE 16 -1 (-3250 3925)(-2825 3925);
WIRE 16 -1 (-3250 3975)(-2825 3975);
WIRE 16 -1 (-3250 4025)(-2825 4025);
WIRE 16 -1 (-3250 4075)(-2825 4075);
WIRE 16 -1 (-3250 2875)(-2825 2875);
WIRE 16 -1 (-3250 2925)(-2825 2925);
WIRE 16 -1 (-3250 2975)(-2825 2975);
WIRE 16 -1 (-3250 3025)(-2825 3025);
WIRE 16 -1 (-3250 3075)(-2825 3075);
WIRE 16 -1 (-3250 3125)(-2825 3125);
WIRE 16 -1 (-3250 3175)(-2825 3175);
WIRE 16 -1 (-3250 3225)(-2825 3225);
WIRE 16 -1 (-3250 3275)(-2825 3275);
WIRE 16 -1 (-3250 3325)(-2825 3325);
WIRE 16 -1 (-3250 3375)(-2825 3375);
WIRE 16 -1 (-3250 3425)(-2825 3425);
WIRE 16 -1 (-3250 3475)(-2825 3475);
WIRE 16 -1 (-3250 3525)(-2825 3525);
WIRE 16 -1 (-3250 3575)(-2825 3575);
WIRE 16 -1 (-3250 3625)(-2825 3625);
WIRE 16 -1 (-3250 3675)(-2825 3675);
WIRE 16 -1 (-3250 3725)(-2825 3725);
WIRE 16 -1 (-3250 525)(-1975 525);
FORCEPROP 2 LAST SIG_NAME M_D_PAR
J 0
(-2625 535);
DISPLAY 0.617021 (-2625 535);
PAINT ORANGE (-2625 535);
WIRE 16 -1 (-3250 575)(-1975 575);
FORCEPROP 2 LAST SIG_NAME M_D_ALERT_N
J 0
(-2625 585);
DISPLAY 0.617021 (-2625 585);
PAINT ORANGE (-2625 585);
WIRE 16 -1 (-3250 625)(-1975 625);
FORCEPROP 2 LAST SIG_NAME M_D_ACT_N
J 0
(-2625 635);
DISPLAY 0.617021 (-2625 635);
PAINT ORANGE (-2625 635);
WIRE 16 -1 (-3250 4125)(-2825 4125);
WIRE 16 -1 (-3250 4175)(-2825 4175);
WIRE 16 -1 (-3250 4225)(-2825 4225);
WIRE 16 -1 (-3250 4275)(-2825 4275);
WIRE 16 -1 (-3250 4325)(-2825 4325);
WIRE 16 -1 (-3250 4375)(-2825 4375);
WIRE 16 -1 (-3250 4425)(-2825 4425);
WIRE 16 -1 (-3250 4475)(-2825 4475);
WIRE 16 -1 (-3250 4525)(-2825 4525);
WIRE 16 -1 (-3250 4575)(-2825 4575);
WIRE 16 -1 (-3250 4625)(-2825 4625);
WIRE 16 -1 (-3250 4675)(-2825 4675);
FORCENOTE
ROOM=CPU0
(-7975 375) 0;
DISPLAY LEFT (-7975 375);
DISPLAY 1.382979 (-7975 375);
PAINT PURPLE (-7975 375);
FORCENOTE
BOM_COST=PROC_SOCKET
(-7975 250) 0;
DISPLAY LEFT (-7975 250);
DISPLAY 1.382979 (-7975 250);
PAINT PURPLE (-7975 250);
QUIT
